FILE_TYPE = MACRO_DRAWING;
SET COLOR_WIRE YELLOW;
SET COLOR_PROP MONO;
SET COLOR_DOT WHITE;
SET COLOR_ARC YELLOW;
SET COLOR_BODY GREEN;
SET COLOR_NOTE MONO;
SET PROP_DISPLAY VALUE;
SET PAGE_NUMBER P58;
FORCEADD OFFPAGE..5
(-6450 525);
FORCEPROP 2 LAST $XR0 79 
J 0
(-6674 525);
DISPLAY 0.638298 (-6674 525);
PAINT MONO (-6674 525);
FORCEPROP 2 LAST $XR1 80 
J 0
(-6764 525);
DISPLAY 0.638298 (-6764 525);
PAINT MONO (-6764 525);
FORCEPROP 2 LAST CDS_LIB mstr_standard
J 0
(-6450 525);
PAINT MONO (-6450 525);
DISPLAY INVISIBLE (-6450 525);
FORCEPROP 1 LAST OFFPAGE TRUE
J 0
(-6125 400);
DISPLAY 1.170213 (-6125 400);
PAINT GREEN (-6125 400);
DISPLAY INVISIBLE (-6125 400);
FORCEPROP 1 LAST COMMENT_BODY TRUE
J 0
(-6350 450);
DISPLAY 1.170213 (-6350 450);
PAINT GREEN (-6350 450);
DISPLAY INVISIBLE (-6350 450);
FORCEPROP 2 LAST PATH I1
J 0
(-6400 600);
DISPLAY 1.021277 (-6400 600);
PAINT ORANGE (-6400 600);
DISPLAY INVISIBLE (-6400 600);
FORCEADD TAP..6
(-5600 825);
FORCEPROP 3 LASTPIN (-5550 825) SIG_NAME M_H_CLK_DP<0>
J 0
(-5540 835);
DISPLAY 0.659574 (-5540 835);
PAINT MONO (-5540 835);
DISPLAY INVISIBLE (-5540 835);
FORCEPROP 1 LASTPIN (-5550 825) BN 0
J 0
(-5602 833);
DISPLAY 0.617021 (-5602 833);
PAINT GREEN (-5602 833);
FORCEPROP 2 LAST CDS_LIB mstr_standard
J 0
(-5600 825);
PAINT MONO (-5600 825);
DISPLAY INVISIBLE (-5600 825);
FORCEPROP 1 LAST BODY_TYPE PLUMBING
J 0
(-5600 775);
DISPLAY 1.595745 (-5600 775);
PAINT GREEN (-5600 775);
DISPLAY INVISIBLE (-5600 775);
FORCEPROP 1 LAST HDL_TAP TRUE
J 0
(-5275 700);
DISPLAY 1.595745 (-5275 700);
PAINT GREEN (-5275 700);
DISPLAY INVISIBLE (-5275 700);
FORCEPROP 1 LAST PATH I10
J 0
(-5602 825);
DISPLAY 0.872340 (-5602 825);
PAINT GREEN (-5602 825);
DISPLAY INVISIBLE (-5602 825);
FORCEADD TAP..6
R 2
(-2875 1575);
FORCEPROP 3 LASTPIN (-2925 1575) SIG_NAME M_H_ODT<3>
J 0
(-2915 1585);
DISPLAY 0.659574 (-2915 1585);
PAINT MONO (-2915 1585);
DISPLAY INVISIBLE (-2915 1585);
FORCEPROP 1 LASTPIN (-2925 1575) BN 3
J 2
(-2873 1583);
DISPLAY 0.617021 (-2873 1583);
PAINT GREEN (-2873 1583);
FORCEPROP 2 LAST CDS_LIB mstr_standard
J 0
(-2875 1575);
PAINT MONO (-2875 1575);
DISPLAY INVISIBLE (-2875 1575);
FORCEPROP 1 LAST BODY_TYPE PLUMBING
J 2
(-2875 1525);
DISPLAY 1.595745 (-2875 1525);
PAINT GREEN (-2875 1525);
DISPLAY INVISIBLE (-2875 1525);
FORCEPROP 1 LAST HDL_TAP TRUE
J 2
(-3200 1450);
DISPLAY 1.595745 (-3200 1450);
PAINT GREEN (-3200 1450);
DISPLAY INVISIBLE (-3200 1450);
FORCEPROP 1 LAST PATH I100
J 2
(-2873 1575);
DISPLAY 0.872340 (-2873 1575);
PAINT GREEN (-2873 1575);
DISPLAY INVISIBLE (-2873 1575);
FORCEADD TAP..6
R 2
(-2875 1525);
FORCEPROP 3 LASTPIN (-2925 1525) SIG_NAME M_H_ODT<2>
J 0
(-2915 1535);
DISPLAY 0.659574 (-2915 1535);
PAINT MONO (-2915 1535);
DISPLAY INVISIBLE (-2915 1535);
FORCEPROP 1 LASTPIN (-2925 1525) BN 2
J 2
(-2873 1533);
DISPLAY 0.617021 (-2873 1533);
PAINT GREEN (-2873 1533);
FORCEPROP 2 LAST CDS_LIB mstr_standard
J 0
(-2875 1525);
PAINT MONO (-2875 1525);
DISPLAY INVISIBLE (-2875 1525);
FORCEPROP 1 LAST BODY_TYPE PLUMBING
J 2
(-2875 1475);
DISPLAY 1.595745 (-2875 1475);
PAINT GREEN (-2875 1475);
DISPLAY INVISIBLE (-2875 1475);
FORCEPROP 1 LAST HDL_TAP TRUE
J 2
(-3200 1400);
DISPLAY 1.595745 (-3200 1400);
PAINT GREEN (-3200 1400);
DISPLAY INVISIBLE (-3200 1400);
FORCEPROP 1 LAST PATH I101
J 2
(-2873 1525);
DISPLAY 0.872340 (-2873 1525);
PAINT GREEN (-2873 1525);
DISPLAY INVISIBLE (-2873 1525);
FORCEADD TAP..6
R 2
(-2875 1475);
FORCEPROP 3 LASTPIN (-2925 1475) SIG_NAME M_H_ODT<1>
J 0
(-2915 1485);
DISPLAY 0.659574 (-2915 1485);
PAINT MONO (-2915 1485);
DISPLAY INVISIBLE (-2915 1485);
FORCEPROP 1 LASTPIN (-2925 1475) BN 1
J 2
(-2873 1483);
DISPLAY 0.617021 (-2873 1483);
PAINT GREEN (-2873 1483);
FORCEPROP 2 LAST CDS_LIB mstr_standard
J 0
(-2875 1475);
PAINT MONO (-2875 1475);
DISPLAY INVISIBLE (-2875 1475);
FORCEPROP 1 LAST BODY_TYPE PLUMBING
J 2
(-2875 1425);
DISPLAY 1.595745 (-2875 1425);
PAINT GREEN (-2875 1425);
DISPLAY INVISIBLE (-2875 1425);
FORCEPROP 1 LAST HDL_TAP TRUE
J 2
(-3200 1350);
DISPLAY 1.595745 (-3200 1350);
PAINT GREEN (-3200 1350);
DISPLAY INVISIBLE (-3200 1350);
FORCEPROP 1 LAST PATH I102
J 2
(-2873 1475);
DISPLAY 0.872340 (-2873 1475);
PAINT GREEN (-2873 1475);
DISPLAY INVISIBLE (-2873 1475);
FORCEADD TAP..6
R 2
(-2875 1675);
FORCEPROP 3 LASTPIN (-2925 1675) SIG_NAME M_H_CKE<0>
J 0
(-2915 1685);
DISPLAY 0.659574 (-2915 1685);
PAINT MONO (-2915 1685);
DISPLAY INVISIBLE (-2915 1685);
FORCEPROP 1 LASTPIN (-2925 1675) BN 0
J 2
(-2873 1683);
DISPLAY 0.617021 (-2873 1683);
PAINT GREEN (-2873 1683);
FORCEPROP 2 LAST CDS_LIB mstr_standard
J 0
(-2875 1675);
PAINT MONO (-2875 1675);
DISPLAY INVISIBLE (-2875 1675);
FORCEPROP 1 LAST BODY_TYPE PLUMBING
J 2
(-2875 1625);
DISPLAY 1.595745 (-2875 1625);
PAINT GREEN (-2875 1625);
DISPLAY INVISIBLE (-2875 1625);
FORCEPROP 1 LAST HDL_TAP TRUE
J 2
(-3200 1550);
DISPLAY 1.595745 (-3200 1550);
PAINT GREEN (-3200 1550);
DISPLAY INVISIBLE (-3200 1550);
FORCEPROP 1 LAST PATH I103
J 2
(-2873 1675);
DISPLAY 0.872340 (-2873 1675);
PAINT GREEN (-2873 1675);
DISPLAY INVISIBLE (-2873 1675);
FORCEADD TAP..6
R 2
(-2875 1725);
FORCEPROP 3 LASTPIN (-2925 1725) SIG_NAME M_H_CKE<1>
J 0
(-2915 1735);
DISPLAY 0.659574 (-2915 1735);
PAINT MONO (-2915 1735);
DISPLAY INVISIBLE (-2915 1735);
FORCEPROP 1 LASTPIN (-2925 1725) BN 1
J 2
(-2873 1733);
DISPLAY 0.617021 (-2873 1733);
PAINT GREEN (-2873 1733);
FORCEPROP 2 LAST CDS_LIB mstr_standard
J 0
(-2875 1725);
PAINT MONO (-2875 1725);
DISPLAY INVISIBLE (-2875 1725);
FORCEPROP 1 LAST BODY_TYPE PLUMBING
J 2
(-2875 1675);
DISPLAY 1.595745 (-2875 1675);
PAINT GREEN (-2875 1675);
DISPLAY INVISIBLE (-2875 1675);
FORCEPROP 1 LAST HDL_TAP TRUE
J 2
(-3200 1600);
DISPLAY 1.595745 (-3200 1600);
PAINT GREEN (-3200 1600);
DISPLAY INVISIBLE (-3200 1600);
FORCEPROP 1 LAST PATH I104
J 2
(-2873 1725);
DISPLAY 0.872340 (-2873 1725);
PAINT GREEN (-2873 1725);
DISPLAY INVISIBLE (-2873 1725);
FORCEADD TAP..6
R 2
(-2875 1775);
FORCEPROP 3 LASTPIN (-2925 1775) SIG_NAME M_H_CKE<2>
J 0
(-2915 1785);
DISPLAY 0.659574 (-2915 1785);
PAINT MONO (-2915 1785);
DISPLAY INVISIBLE (-2915 1785);
FORCEPROP 1 LASTPIN (-2925 1775) BN 2
J 2
(-2873 1783);
DISPLAY 0.617021 (-2873 1783);
PAINT GREEN (-2873 1783);
FORCEPROP 2 LAST CDS_LIB mstr_standard
J 0
(-2875 1775);
PAINT MONO (-2875 1775);
DISPLAY INVISIBLE (-2875 1775);
FORCEPROP 1 LAST BODY_TYPE PLUMBING
J 2
(-2875 1725);
DISPLAY 1.595745 (-2875 1725);
PAINT GREEN (-2875 1725);
DISPLAY INVISIBLE (-2875 1725);
FORCEPROP 1 LAST HDL_TAP TRUE
J 2
(-3200 1650);
DISPLAY 1.595745 (-3200 1650);
PAINT GREEN (-3200 1650);
DISPLAY INVISIBLE (-3200 1650);
FORCEPROP 1 LAST PATH I105
J 2
(-2873 1775);
DISPLAY 0.872340 (-2873 1775);
PAINT GREEN (-2873 1775);
DISPLAY INVISIBLE (-2873 1775);
FORCEADD TAP..6
R 2
(-2875 1825);
FORCEPROP 3 LASTPIN (-2925 1825) SIG_NAME M_H_CKE<3>
J 0
(-2915 1835);
DISPLAY 0.659574 (-2915 1835);
PAINT MONO (-2915 1835);
DISPLAY INVISIBLE (-2915 1835);
FORCEPROP 1 LASTPIN (-2925 1825) BN 3
J 2
(-2873 1833);
DISPLAY 0.617021 (-2873 1833);
PAINT GREEN (-2873 1833);
FORCEPROP 2 LAST CDS_LIB mstr_standard
J 0
(-2875 1825);
PAINT MONO (-2875 1825);
DISPLAY INVISIBLE (-2875 1825);
FORCEPROP 1 LAST BODY_TYPE PLUMBING
J 2
(-2875 1775);
DISPLAY 1.595745 (-2875 1775);
PAINT GREEN (-2875 1775);
DISPLAY INVISIBLE (-2875 1775);
FORCEPROP 1 LAST HDL_TAP TRUE
J 2
(-3200 1700);
DISPLAY 1.595745 (-3200 1700);
PAINT GREEN (-3200 1700);
DISPLAY INVISIBLE (-3200 1700);
FORCEPROP 1 LAST PATH I106
J 2
(-2873 1825);
DISPLAY 0.872340 (-2873 1825);
PAINT GREEN (-2873 1825);
DISPLAY INVISIBLE (-2873 1825);
FORCEADD TAP..6
R 2
(-2875 1925);
FORCEPROP 3 LASTPIN (-2925 1925) SIG_NAME M_H_MA<0>
J 0
(-2915 1935);
DISPLAY 0.659574 (-2915 1935);
PAINT MONO (-2915 1935);
DISPLAY INVISIBLE (-2915 1935);
FORCEPROP 1 LASTPIN (-2925 1925) BN 0
J 2
(-2873 1933);
DISPLAY 0.617021 (-2873 1933);
PAINT GREEN (-2873 1933);
FORCEPROP 2 LAST CDS_LIB mstr_standard
J 0
(-2875 1925);
PAINT MONO (-2875 1925);
DISPLAY INVISIBLE (-2875 1925);
FORCEPROP 1 LAST BODY_TYPE PLUMBING
J 2
(-2875 1875);
DISPLAY 1.595745 (-2875 1875);
PAINT GREEN (-2875 1875);
DISPLAY INVISIBLE (-2875 1875);
FORCEPROP 1 LAST HDL_TAP TRUE
J 2
(-3200 1800);
DISPLAY 1.595745 (-3200 1800);
PAINT GREEN (-3200 1800);
DISPLAY INVISIBLE (-3200 1800);
FORCEPROP 1 LAST PATH I107
J 2
(-2873 1925);
DISPLAY 0.872340 (-2873 1925);
PAINT GREEN (-2873 1925);
DISPLAY INVISIBLE (-2873 1925);
FORCEADD TAP..6
R 2
(-2875 1975);
FORCEPROP 3 LASTPIN (-2925 1975) SIG_NAME M_H_MA<1>
J 0
(-2915 1985);
DISPLAY 0.659574 (-2915 1985);
PAINT MONO (-2915 1985);
DISPLAY INVISIBLE (-2915 1985);
FORCEPROP 1 LASTPIN (-2925 1975) BN 1
J 2
(-2873 1983);
DISPLAY 0.617021 (-2873 1983);
PAINT GREEN (-2873 1983);
FORCEPROP 2 LAST CDS_LIB mstr_standard
J 0
(-2875 1975);
PAINT MONO (-2875 1975);
DISPLAY INVISIBLE (-2875 1975);
FORCEPROP 1 LAST BODY_TYPE PLUMBING
J 2
(-2875 1925);
DISPLAY 1.595745 (-2875 1925);
PAINT GREEN (-2875 1925);
DISPLAY INVISIBLE (-2875 1925);
FORCEPROP 1 LAST HDL_TAP TRUE
J 2
(-3200 1850);
DISPLAY 1.595745 (-3200 1850);
PAINT GREEN (-3200 1850);
DISPLAY INVISIBLE (-3200 1850);
FORCEPROP 1 LAST PATH I108
J 2
(-2873 1975);
DISPLAY 0.872340 (-2873 1975);
PAINT GREEN (-2873 1975);
DISPLAY INVISIBLE (-2873 1975);
FORCEADD TAP..6
R 2
(-2875 2075);
FORCEPROP 3 LASTPIN (-2925 2075) SIG_NAME M_H_MA<3>
J 0
(-2915 2085);
DISPLAY 0.659574 (-2915 2085);
PAINT MONO (-2915 2085);
DISPLAY INVISIBLE (-2915 2085);
FORCEPROP 1 LASTPIN (-2925 2075) BN 3
J 2
(-2873 2083);
DISPLAY 0.617021 (-2873 2083);
PAINT GREEN (-2873 2083);
FORCEPROP 2 LAST CDS_LIB mstr_standard
J 0
(-2875 2075);
PAINT MONO (-2875 2075);
DISPLAY INVISIBLE (-2875 2075);
FORCEPROP 1 LAST BODY_TYPE PLUMBING
J 2
(-2875 2025);
DISPLAY 1.595745 (-2875 2025);
PAINT GREEN (-2875 2025);
DISPLAY INVISIBLE (-2875 2025);
FORCEPROP 1 LAST HDL_TAP TRUE
J 2
(-3200 1950);
DISPLAY 1.595745 (-3200 1950);
PAINT GREEN (-3200 1950);
DISPLAY INVISIBLE (-3200 1950);
FORCEPROP 1 LAST PATH I109
J 2
(-2873 2075);
DISPLAY 0.872340 (-2873 2075);
PAINT GREEN (-2873 2075);
DISPLAY INVISIBLE (-2873 2075);
FORCEADD TAP..6
(-5600 925);
FORCEPROP 3 LASTPIN (-5550 925) SIG_NAME M_H_CLK_DP<2>
J 0
(-5540 935);
DISPLAY 0.659574 (-5540 935);
PAINT MONO (-5540 935);
DISPLAY INVISIBLE (-5540 935);
FORCEPROP 1 LASTPIN (-5550 925) BN 2
J 0
(-5602 933);
DISPLAY 0.617021 (-5602 933);
PAINT GREEN (-5602 933);
FORCEPROP 2 LAST CDS_LIB mstr_standard
J 0
(-5600 925);
PAINT MONO (-5600 925);
DISPLAY INVISIBLE (-5600 925);
FORCEPROP 1 LAST BODY_TYPE PLUMBING
J 0
(-5600 875);
DISPLAY 1.595745 (-5600 875);
PAINT GREEN (-5600 875);
DISPLAY INVISIBLE (-5600 875);
FORCEPROP 1 LAST HDL_TAP TRUE
J 0
(-5275 800);
DISPLAY 1.595745 (-5275 800);
PAINT GREEN (-5275 800);
DISPLAY INVISIBLE (-5275 800);
FORCEPROP 1 LAST PATH I11
J 0
(-5602 925);
DISPLAY 0.872340 (-5602 925);
PAINT GREEN (-5602 925);
DISPLAY INVISIBLE (-5602 925);
FORCEADD TAP..6
R 2
(-2875 2025);
FORCEPROP 3 LASTPIN (-2925 2025) SIG_NAME M_H_MA<2>
J 0
(-2915 2035);
DISPLAY 0.659574 (-2915 2035);
PAINT MONO (-2915 2035);
DISPLAY INVISIBLE (-2915 2035);
FORCEPROP 1 LASTPIN (-2925 2025) BN 2
J 2
(-2873 2033);
DISPLAY 0.617021 (-2873 2033);
PAINT GREEN (-2873 2033);
FORCEPROP 2 LAST CDS_LIB mstr_standard
J 0
(-2875 2025);
PAINT MONO (-2875 2025);
DISPLAY INVISIBLE (-2875 2025);
FORCEPROP 1 LAST BODY_TYPE PLUMBING
J 2
(-2875 1975);
DISPLAY 1.595745 (-2875 1975);
PAINT GREEN (-2875 1975);
DISPLAY INVISIBLE (-2875 1975);
FORCEPROP 1 LAST HDL_TAP TRUE
J 2
(-3200 1900);
DISPLAY 1.595745 (-3200 1900);
PAINT GREEN (-3200 1900);
DISPLAY INVISIBLE (-3200 1900);
FORCEPROP 1 LAST PATH I110
J 2
(-2873 2025);
DISPLAY 0.872340 (-2873 2025);
PAINT GREEN (-2873 2025);
DISPLAY INVISIBLE (-2873 2025);
FORCEADD TAP..6
R 2
(-2875 2125);
FORCEPROP 3 LASTPIN (-2925 2125) SIG_NAME M_H_MA<4>
J 0
(-2915 2135);
DISPLAY 0.659574 (-2915 2135);
PAINT MONO (-2915 2135);
DISPLAY INVISIBLE (-2915 2135);
FORCEPROP 1 LASTPIN (-2925 2125) BN 4
J 2
(-2873 2133);
DISPLAY 0.617021 (-2873 2133);
PAINT GREEN (-2873 2133);
FORCEPROP 2 LAST CDS_LIB mstr_standard
J 0
(-2875 2125);
PAINT MONO (-2875 2125);
DISPLAY INVISIBLE (-2875 2125);
FORCEPROP 1 LAST BODY_TYPE PLUMBING
J 2
(-2875 2075);
DISPLAY 1.595745 (-2875 2075);
PAINT GREEN (-2875 2075);
DISPLAY INVISIBLE (-2875 2075);
FORCEPROP 1 LAST HDL_TAP TRUE
J 2
(-3200 2000);
DISPLAY 1.595745 (-3200 2000);
PAINT GREEN (-3200 2000);
DISPLAY INVISIBLE (-3200 2000);
FORCEPROP 1 LAST PATH I111
J 2
(-2873 2125);
DISPLAY 0.872340 (-2873 2125);
PAINT GREEN (-2873 2125);
DISPLAY INVISIBLE (-2873 2125);
FORCEADD TAP..6
R 2
(-2875 2175);
FORCEPROP 3 LASTPIN (-2925 2175) SIG_NAME M_H_MA<5>
J 0
(-2915 2185);
DISPLAY 0.659574 (-2915 2185);
PAINT MONO (-2915 2185);
DISPLAY INVISIBLE (-2915 2185);
FORCEPROP 1 LASTPIN (-2925 2175) BN 5
J 2
(-2873 2183);
DISPLAY 0.617021 (-2873 2183);
PAINT GREEN (-2873 2183);
FORCEPROP 2 LAST CDS_LIB mstr_standard
J 0
(-2875 2175);
PAINT MONO (-2875 2175);
DISPLAY INVISIBLE (-2875 2175);
FORCEPROP 1 LAST BODY_TYPE PLUMBING
J 2
(-2875 2125);
DISPLAY 1.595745 (-2875 2125);
PAINT GREEN (-2875 2125);
DISPLAY INVISIBLE (-2875 2125);
FORCEPROP 1 LAST HDL_TAP TRUE
J 2
(-3200 2050);
DISPLAY 1.595745 (-3200 2050);
PAINT GREEN (-3200 2050);
DISPLAY INVISIBLE (-3200 2050);
FORCEPROP 1 LAST PATH I112
J 2
(-2873 2175);
DISPLAY 0.872340 (-2873 2175);
PAINT GREEN (-2873 2175);
DISPLAY INVISIBLE (-2873 2175);
FORCEADD TAP..6
R 2
(-2875 2225);
FORCEPROP 3 LASTPIN (-2925 2225) SIG_NAME M_H_MA<6>
J 0
(-2915 2235);
DISPLAY 0.659574 (-2915 2235);
PAINT MONO (-2915 2235);
DISPLAY INVISIBLE (-2915 2235);
FORCEPROP 1 LASTPIN (-2925 2225) BN 6
J 2
(-2873 2233);
DISPLAY 0.617021 (-2873 2233);
PAINT GREEN (-2873 2233);
FORCEPROP 2 LAST CDS_LIB mstr_standard
J 0
(-2875 2225);
PAINT MONO (-2875 2225);
DISPLAY INVISIBLE (-2875 2225);
FORCEPROP 1 LAST BODY_TYPE PLUMBING
J 2
(-2875 2175);
DISPLAY 1.595745 (-2875 2175);
PAINT GREEN (-2875 2175);
DISPLAY INVISIBLE (-2875 2175);
FORCEPROP 1 LAST HDL_TAP TRUE
J 2
(-3200 2100);
DISPLAY 1.595745 (-3200 2100);
PAINT GREEN (-3200 2100);
DISPLAY INVISIBLE (-3200 2100);
FORCEPROP 1 LAST PATH I113
J 2
(-2873 2225);
DISPLAY 0.872340 (-2873 2225);
PAINT GREEN (-2873 2225);
DISPLAY INVISIBLE (-2873 2225);
FORCEADD TAP..6
R 2
(-2875 2325);
FORCEPROP 3 LASTPIN (-2925 2325) SIG_NAME M_H_MA<8>
J 0
(-2915 2335);
DISPLAY 0.659574 (-2915 2335);
PAINT MONO (-2915 2335);
DISPLAY INVISIBLE (-2915 2335);
FORCEPROP 1 LASTPIN (-2925 2325) BN 8
J 2
(-2873 2333);
DISPLAY 0.617021 (-2873 2333);
PAINT GREEN (-2873 2333);
FORCEPROP 2 LAST CDS_LIB mstr_standard
J 0
(-2875 2325);
PAINT MONO (-2875 2325);
DISPLAY INVISIBLE (-2875 2325);
FORCEPROP 1 LAST BODY_TYPE PLUMBING
J 2
(-2875 2275);
DISPLAY 1.595745 (-2875 2275);
PAINT GREEN (-2875 2275);
DISPLAY INVISIBLE (-2875 2275);
FORCEPROP 1 LAST HDL_TAP TRUE
J 2
(-3200 2200);
DISPLAY 1.595745 (-3200 2200);
PAINT GREEN (-3200 2200);
DISPLAY INVISIBLE (-3200 2200);
FORCEPROP 1 LAST PATH I114
J 2
(-2873 2325);
DISPLAY 0.872340 (-2873 2325);
PAINT GREEN (-2873 2325);
DISPLAY INVISIBLE (-2873 2325);
FORCEADD TAP..6
R 2
(-2875 2275);
FORCEPROP 3 LASTPIN (-2925 2275) SIG_NAME M_H_MA<7>
J 0
(-2915 2285);
DISPLAY 0.659574 (-2915 2285);
PAINT MONO (-2915 2285);
DISPLAY INVISIBLE (-2915 2285);
FORCEPROP 1 LASTPIN (-2925 2275) BN 7
J 2
(-2873 2283);
DISPLAY 0.617021 (-2873 2283);
PAINT GREEN (-2873 2283);
FORCEPROP 2 LAST CDS_LIB mstr_standard
J 0
(-2875 2275);
PAINT MONO (-2875 2275);
DISPLAY INVISIBLE (-2875 2275);
FORCEPROP 1 LAST BODY_TYPE PLUMBING
J 2
(-2875 2225);
DISPLAY 1.595745 (-2875 2225);
PAINT GREEN (-2875 2225);
DISPLAY INVISIBLE (-2875 2225);
FORCEPROP 1 LAST HDL_TAP TRUE
J 2
(-3200 2150);
DISPLAY 1.595745 (-3200 2150);
PAINT GREEN (-3200 2150);
DISPLAY INVISIBLE (-3200 2150);
FORCEPROP 1 LAST PATH I115
J 2
(-2873 2275);
DISPLAY 0.872340 (-2873 2275);
PAINT GREEN (-2873 2275);
DISPLAY INVISIBLE (-2873 2275);
FORCEADD TAP..6
R 2
(-2875 2475);
FORCEPROP 3 LASTPIN (-2925 2475) SIG_NAME M_H_MA<11>
J 0
(-2915 2485);
DISPLAY 0.659574 (-2915 2485);
PAINT MONO (-2915 2485);
DISPLAY INVISIBLE (-2915 2485);
FORCEPROP 1 LASTPIN (-2925 2475) BN 11
J 2
(-2873 2483);
DISPLAY 0.617021 (-2873 2483);
PAINT GREEN (-2873 2483);
FORCEPROP 2 LAST CDS_LIB mstr_standard
J 0
(-2875 2475);
PAINT MONO (-2875 2475);
DISPLAY INVISIBLE (-2875 2475);
FORCEPROP 1 LAST BODY_TYPE PLUMBING
J 2
(-2875 2425);
DISPLAY 1.595745 (-2875 2425);
PAINT GREEN (-2875 2425);
DISPLAY INVISIBLE (-2875 2425);
FORCEPROP 1 LAST HDL_TAP TRUE
J 2
(-3200 2350);
DISPLAY 1.595745 (-3200 2350);
PAINT GREEN (-3200 2350);
DISPLAY INVISIBLE (-3200 2350);
FORCEPROP 1 LAST PATH I116
J 2
(-2873 2475);
DISPLAY 0.872340 (-2873 2475);
PAINT GREEN (-2873 2475);
DISPLAY INVISIBLE (-2873 2475);
FORCEADD TAP..6
R 2
(-2875 2425);
FORCEPROP 3 LASTPIN (-2925 2425) SIG_NAME M_H_MA<10>
J 0
(-2915 2435);
DISPLAY 0.659574 (-2915 2435);
PAINT MONO (-2915 2435);
DISPLAY INVISIBLE (-2915 2435);
FORCEPROP 1 LASTPIN (-2925 2425) BN 10
J 2
(-2873 2433);
DISPLAY 0.617021 (-2873 2433);
PAINT GREEN (-2873 2433);
FORCEPROP 2 LAST CDS_LIB mstr_standard
J 0
(-2875 2425);
PAINT MONO (-2875 2425);
DISPLAY INVISIBLE (-2875 2425);
FORCEPROP 1 LAST BODY_TYPE PLUMBING
J 2
(-2875 2375);
DISPLAY 1.595745 (-2875 2375);
PAINT GREEN (-2875 2375);
DISPLAY INVISIBLE (-2875 2375);
FORCEPROP 1 LAST HDL_TAP TRUE
J 2
(-3200 2300);
DISPLAY 1.595745 (-3200 2300);
PAINT GREEN (-3200 2300);
DISPLAY INVISIBLE (-3200 2300);
FORCEPROP 1 LAST PATH I117
J 2
(-2873 2425);
DISPLAY 0.872340 (-2873 2425);
PAINT GREEN (-2873 2425);
DISPLAY INVISIBLE (-2873 2425);
FORCEADD TAP..6
R 2
(-2875 2375);
FORCEPROP 3 LASTPIN (-2925 2375) SIG_NAME M_H_MA<9>
J 0
(-2915 2385);
DISPLAY 0.659574 (-2915 2385);
PAINT MONO (-2915 2385);
DISPLAY INVISIBLE (-2915 2385);
FORCEPROP 1 LASTPIN (-2925 2375) BN 9
J 2
(-2873 2383);
DISPLAY 0.617021 (-2873 2383);
PAINT GREEN (-2873 2383);
FORCEPROP 2 LAST CDS_LIB mstr_standard
J 0
(-2875 2375);
PAINT MONO (-2875 2375);
DISPLAY INVISIBLE (-2875 2375);
FORCEPROP 1 LAST BODY_TYPE PLUMBING
J 2
(-2875 2325);
DISPLAY 1.595745 (-2875 2325);
PAINT GREEN (-2875 2325);
DISPLAY INVISIBLE (-2875 2325);
FORCEPROP 1 LAST HDL_TAP TRUE
J 2
(-3200 2250);
DISPLAY 1.595745 (-3200 2250);
PAINT GREEN (-3200 2250);
DISPLAY INVISIBLE (-3200 2250);
FORCEPROP 1 LAST PATH I118
J 2
(-2873 2375);
DISPLAY 0.872340 (-2873 2375);
PAINT GREEN (-2873 2375);
DISPLAY INVISIBLE (-2873 2375);
FORCEADD TAP..6
R 2
(-2875 2525);
FORCEPROP 3 LASTPIN (-2925 2525) SIG_NAME M_H_MA<12>
J 0
(-2915 2535);
DISPLAY 0.659574 (-2915 2535);
PAINT MONO (-2915 2535);
DISPLAY INVISIBLE (-2915 2535);
FORCEPROP 1 LASTPIN (-2925 2525) BN 12
J 2
(-2873 2533);
DISPLAY 0.617021 (-2873 2533);
PAINT GREEN (-2873 2533);
FORCEPROP 2 LAST CDS_LIB mstr_standard
J 0
(-2875 2525);
PAINT MONO (-2875 2525);
DISPLAY INVISIBLE (-2875 2525);
FORCEPROP 1 LAST BODY_TYPE PLUMBING
J 2
(-2875 2475);
DISPLAY 1.595745 (-2875 2475);
PAINT GREEN (-2875 2475);
DISPLAY INVISIBLE (-2875 2475);
FORCEPROP 1 LAST HDL_TAP TRUE
J 2
(-3200 2400);
DISPLAY 1.595745 (-3200 2400);
PAINT GREEN (-3200 2400);
DISPLAY INVISIBLE (-3200 2400);
FORCEPROP 1 LAST PATH I119
J 2
(-2873 2525);
DISPLAY 0.872340 (-2873 2525);
PAINT GREEN (-2873 2525);
DISPLAY INVISIBLE (-2873 2525);
FORCEADD TAP..6
(-5600 975);
FORCEPROP 3 LASTPIN (-5550 975) SIG_NAME M_H_CLK_DP<3>
J 0
(-5540 985);
DISPLAY 0.659574 (-5540 985);
PAINT MONO (-5540 985);
DISPLAY INVISIBLE (-5540 985);
FORCEPROP 1 LASTPIN (-5550 975) BN 3
J 0
(-5602 983);
DISPLAY 0.617021 (-5602 983);
PAINT GREEN (-5602 983);
FORCEPROP 2 LAST CDS_LIB mstr_standard
J 0
(-5600 975);
PAINT MONO (-5600 975);
DISPLAY INVISIBLE (-5600 975);
FORCEPROP 1 LAST BODY_TYPE PLUMBING
J 0
(-5600 925);
DISPLAY 1.595745 (-5600 925);
PAINT GREEN (-5600 925);
DISPLAY INVISIBLE (-5600 925);
FORCEPROP 1 LAST HDL_TAP TRUE
J 0
(-5275 850);
DISPLAY 1.595745 (-5275 850);
PAINT GREEN (-5275 850);
DISPLAY INVISIBLE (-5275 850);
FORCEPROP 1 LAST PATH I12
J 0
(-5602 975);
DISPLAY 0.872340 (-5602 975);
PAINT GREEN (-5602 975);
DISPLAY INVISIBLE (-5602 975);
FORCEADD TAP..6
R 2
(-2875 2575);
FORCEPROP 3 LASTPIN (-2925 2575) SIG_NAME M_H_MA<13>
J 0
(-2915 2585);
DISPLAY 0.659574 (-2915 2585);
PAINT MONO (-2915 2585);
DISPLAY INVISIBLE (-2915 2585);
FORCEPROP 1 LASTPIN (-2925 2575) BN 13
J 2
(-2873 2583);
DISPLAY 0.617021 (-2873 2583);
PAINT GREEN (-2873 2583);
FORCEPROP 2 LAST CDS_LIB mstr_standard
J 0
(-2875 2575);
PAINT MONO (-2875 2575);
DISPLAY INVISIBLE (-2875 2575);
FORCEPROP 1 LAST BODY_TYPE PLUMBING
J 2
(-2875 2525);
DISPLAY 1.595745 (-2875 2525);
PAINT GREEN (-2875 2525);
DISPLAY INVISIBLE (-2875 2525);
FORCEPROP 1 LAST HDL_TAP TRUE
J 2
(-3200 2450);
DISPLAY 1.595745 (-3200 2450);
PAINT GREEN (-3200 2450);
DISPLAY INVISIBLE (-3200 2450);
FORCEPROP 1 LAST PATH I120
J 2
(-2873 2575);
DISPLAY 0.872340 (-2873 2575);
PAINT GREEN (-2873 2575);
DISPLAY INVISIBLE (-2873 2575);
FORCEADD TAP..6
R 2
(-2875 2625);
FORCEPROP 3 LASTPIN (-2925 2625) SIG_NAME M_H_MA<14>
J 0
(-2915 2635);
DISPLAY 0.659574 (-2915 2635);
PAINT MONO (-2915 2635);
DISPLAY INVISIBLE (-2915 2635);
FORCEPROP 1 LASTPIN (-2925 2625) BN 14
J 2
(-2873 2633);
DISPLAY 0.617021 (-2873 2633);
PAINT GREEN (-2873 2633);
FORCEPROP 2 LAST CDS_LIB mstr_standard
J 0
(-2875 2625);
PAINT MONO (-2875 2625);
DISPLAY INVISIBLE (-2875 2625);
FORCEPROP 1 LAST BODY_TYPE PLUMBING
J 2
(-2875 2575);
DISPLAY 1.595745 (-2875 2575);
PAINT GREEN (-2875 2575);
DISPLAY INVISIBLE (-2875 2575);
FORCEPROP 1 LAST HDL_TAP TRUE
J 2
(-3200 2500);
DISPLAY 1.595745 (-3200 2500);
PAINT GREEN (-3200 2500);
DISPLAY INVISIBLE (-3200 2500);
FORCEPROP 1 LAST PATH I121
J 2
(-2873 2625);
DISPLAY 0.872340 (-2873 2625);
PAINT GREEN (-2873 2625);
DISPLAY INVISIBLE (-2873 2625);
FORCEADD TAP..6
R 2
(-2875 2675);
FORCEPROP 3 LASTPIN (-2925 2675) SIG_NAME M_H_MA<15>
J 0
(-2915 2685);
DISPLAY 0.659574 (-2915 2685);
PAINT MONO (-2915 2685);
DISPLAY INVISIBLE (-2915 2685);
FORCEPROP 1 LASTPIN (-2925 2675) BN 15
J 2
(-2873 2683);
DISPLAY 0.617021 (-2873 2683);
PAINT GREEN (-2873 2683);
FORCEPROP 2 LAST CDS_LIB mstr_standard
J 0
(-2875 2675);
PAINT MONO (-2875 2675);
DISPLAY INVISIBLE (-2875 2675);
FORCEPROP 1 LAST BODY_TYPE PLUMBING
J 2
(-2875 2625);
DISPLAY 1.595745 (-2875 2625);
PAINT GREEN (-2875 2625);
DISPLAY INVISIBLE (-2875 2625);
FORCEPROP 1 LAST HDL_TAP TRUE
J 2
(-3200 2550);
DISPLAY 1.595745 (-3200 2550);
PAINT GREEN (-3200 2550);
DISPLAY INVISIBLE (-3200 2550);
FORCEPROP 1 LAST PATH I122
J 2
(-2873 2675);
DISPLAY 0.872340 (-2873 2675);
PAINT GREEN (-2873 2675);
DISPLAY INVISIBLE (-2873 2675);
FORCEADD TAP..6
R 2
(-2875 2725);
FORCEPROP 3 LASTPIN (-2925 2725) SIG_NAME M_H_MA<16>
J 0
(-2915 2735);
DISPLAY 0.659574 (-2915 2735);
PAINT MONO (-2915 2735);
DISPLAY INVISIBLE (-2915 2735);
FORCEPROP 1 LASTPIN (-2925 2725) BN 16
J 2
(-2873 2733);
DISPLAY 0.617021 (-2873 2733);
PAINT GREEN (-2873 2733);
FORCEPROP 2 LAST CDS_LIB mstr_standard
J 0
(-2875 2725);
PAINT MONO (-2875 2725);
DISPLAY INVISIBLE (-2875 2725);
FORCEPROP 1 LAST BODY_TYPE PLUMBING
J 2
(-2875 2675);
DISPLAY 1.595745 (-2875 2675);
PAINT GREEN (-2875 2675);
DISPLAY INVISIBLE (-2875 2675);
FORCEPROP 1 LAST HDL_TAP TRUE
J 2
(-3200 2600);
DISPLAY 1.595745 (-3200 2600);
PAINT GREEN (-3200 2600);
DISPLAY INVISIBLE (-3200 2600);
FORCEPROP 1 LAST PATH I123
J 2
(-2873 2725);
DISPLAY 0.872340 (-2873 2725);
PAINT GREEN (-2873 2725);
DISPLAY INVISIBLE (-2873 2725);
FORCEADD TAP..6
R 2
(-2875 2775);
FORCEPROP 3 LASTPIN (-2925 2775) SIG_NAME M_H_MA<17>
J 0
(-2915 2785);
DISPLAY 0.659574 (-2915 2785);
PAINT MONO (-2915 2785);
DISPLAY INVISIBLE (-2915 2785);
FORCEPROP 1 LASTPIN (-2925 2775) BN 17
J 2
(-2873 2783);
DISPLAY 0.617021 (-2873 2783);
PAINT GREEN (-2873 2783);
FORCEPROP 2 LAST CDS_LIB mstr_standard
J 0
(-2875 2775);
PAINT MONO (-2875 2775);
DISPLAY INVISIBLE (-2875 2775);
FORCEPROP 1 LAST BODY_TYPE PLUMBING
J 2
(-2875 2725);
DISPLAY 1.595745 (-2875 2725);
PAINT GREEN (-2875 2725);
DISPLAY INVISIBLE (-2875 2725);
FORCEPROP 1 LAST HDL_TAP TRUE
J 2
(-3200 2650);
DISPLAY 1.595745 (-3200 2650);
PAINT GREEN (-3200 2650);
DISPLAY INVISIBLE (-3200 2650);
FORCEPROP 1 LAST PATH I124
J 2
(-2873 2775);
DISPLAY 0.872340 (-2873 2775);
PAINT GREEN (-2873 2775);
DISPLAY INVISIBLE (-2873 2775);
FORCEADD TAP..6
R 2
(-2875 2925);
FORCEPROP 3 LASTPIN (-2925 2925) SIG_NAME M_H_DQS_DN<1>
J 0
(-2915 2935);
DISPLAY 0.659574 (-2915 2935);
PAINT MONO (-2915 2935);
DISPLAY INVISIBLE (-2915 2935);
FORCEPROP 1 LASTPIN (-2925 2925) BN 1
J 2
(-2873 2933);
DISPLAY 0.617021 (-2873 2933);
PAINT GREEN (-2873 2933);
FORCEPROP 2 LAST CDS_LIB mstr_standard
J 0
(-2875 2925);
PAINT MONO (-2875 2925);
DISPLAY INVISIBLE (-2875 2925);
FORCEPROP 1 LAST BODY_TYPE PLUMBING
J 2
(-2875 2875);
DISPLAY 1.595745 (-2875 2875);
PAINT GREEN (-2875 2875);
DISPLAY INVISIBLE (-2875 2875);
FORCEPROP 1 LAST HDL_TAP TRUE
J 2
(-3200 2800);
DISPLAY 1.595745 (-3200 2800);
PAINT GREEN (-3200 2800);
DISPLAY INVISIBLE (-3200 2800);
FORCEPROP 1 LAST PATH I125
J 2
(-2873 2925);
DISPLAY 0.872340 (-2873 2925);
PAINT GREEN (-2873 2925);
DISPLAY INVISIBLE (-2873 2925);
FORCEADD TAP..6
R 2
(-2875 2975);
FORCEPROP 3 LASTPIN (-2925 2975) SIG_NAME M_H_DQS_DN<2>
J 0
(-2915 2985);
DISPLAY 0.659574 (-2915 2985);
PAINT MONO (-2915 2985);
DISPLAY INVISIBLE (-2915 2985);
FORCEPROP 1 LASTPIN (-2925 2975) BN 2
J 2
(-2873 2983);
DISPLAY 0.617021 (-2873 2983);
PAINT GREEN (-2873 2983);
FORCEPROP 2 LAST CDS_LIB mstr_standard
J 0
(-2875 2975);
PAINT MONO (-2875 2975);
DISPLAY INVISIBLE (-2875 2975);
FORCEPROP 1 LAST BODY_TYPE PLUMBING
J 2
(-2875 2925);
DISPLAY 1.595745 (-2875 2925);
PAINT GREEN (-2875 2925);
DISPLAY INVISIBLE (-2875 2925);
FORCEPROP 1 LAST HDL_TAP TRUE
J 2
(-3200 2850);
DISPLAY 1.595745 (-3200 2850);
PAINT GREEN (-3200 2850);
DISPLAY INVISIBLE (-3200 2850);
FORCEPROP 1 LAST PATH I126
J 2
(-2873 2975);
DISPLAY 0.872340 (-2873 2975);
PAINT GREEN (-2873 2975);
DISPLAY INVISIBLE (-2873 2975);
FORCEADD TAP..6
R 2
(-2875 2875);
FORCEPROP 3 LASTPIN (-2925 2875) SIG_NAME M_H_DQS_DN<0>
J 0
(-2915 2885);
DISPLAY 0.659574 (-2915 2885);
PAINT MONO (-2915 2885);
DISPLAY INVISIBLE (-2915 2885);
FORCEPROP 1 LASTPIN (-2925 2875) BN 0
J 2
(-2873 2883);
DISPLAY 0.617021 (-2873 2883);
PAINT GREEN (-2873 2883);
FORCEPROP 2 LAST CDS_LIB mstr_standard
J 0
(-2875 2875);
PAINT MONO (-2875 2875);
DISPLAY INVISIBLE (-2875 2875);
FORCEPROP 1 LAST BODY_TYPE PLUMBING
J 2
(-2875 2825);
DISPLAY 1.595745 (-2875 2825);
PAINT GREEN (-2875 2825);
DISPLAY INVISIBLE (-2875 2825);
FORCEPROP 1 LAST HDL_TAP TRUE
J 2
(-3200 2750);
DISPLAY 1.595745 (-3200 2750);
PAINT GREEN (-3200 2750);
DISPLAY INVISIBLE (-3200 2750);
FORCEPROP 1 LAST PATH I127
J 2
(-2873 2875);
DISPLAY 0.872340 (-2873 2875);
PAINT GREEN (-2873 2875);
DISPLAY INVISIBLE (-2873 2875);
FORCEADD TAP..6
R 2
(-2875 3075);
FORCEPROP 3 LASTPIN (-2925 3075) SIG_NAME M_H_DQS_DN<4>
J 0
(-2915 3085);
DISPLAY 0.659574 (-2915 3085);
PAINT MONO (-2915 3085);
DISPLAY INVISIBLE (-2915 3085);
FORCEPROP 1 LASTPIN (-2925 3075) BN 4
J 2
(-2873 3083);
DISPLAY 0.617021 (-2873 3083);
PAINT GREEN (-2873 3083);
FORCEPROP 2 LAST CDS_LIB mstr_standard
J 0
(-2875 3075);
PAINT MONO (-2875 3075);
DISPLAY INVISIBLE (-2875 3075);
FORCEPROP 1 LAST BODY_TYPE PLUMBING
J 2
(-2875 3025);
DISPLAY 1.595745 (-2875 3025);
PAINT GREEN (-2875 3025);
DISPLAY INVISIBLE (-2875 3025);
FORCEPROP 1 LAST HDL_TAP TRUE
J 2
(-3200 2950);
DISPLAY 1.595745 (-3200 2950);
PAINT GREEN (-3200 2950);
DISPLAY INVISIBLE (-3200 2950);
FORCEPROP 1 LAST PATH I128
J 2
(-2873 3075);
DISPLAY 0.872340 (-2873 3075);
PAINT GREEN (-2873 3075);
DISPLAY INVISIBLE (-2873 3075);
FORCEADD TAP..6
R 2
(-2875 3025);
FORCEPROP 3 LASTPIN (-2925 3025) SIG_NAME M_H_DQS_DN<3>
J 0
(-2915 3035);
DISPLAY 0.659574 (-2915 3035);
PAINT MONO (-2915 3035);
DISPLAY INVISIBLE (-2915 3035);
FORCEPROP 1 LASTPIN (-2925 3025) BN 3
J 2
(-2873 3033);
DISPLAY 0.617021 (-2873 3033);
PAINT GREEN (-2873 3033);
FORCEPROP 2 LAST CDS_LIB mstr_standard
J 0
(-2875 3025);
PAINT MONO (-2875 3025);
DISPLAY INVISIBLE (-2875 3025);
FORCEPROP 1 LAST BODY_TYPE PLUMBING
J 2
(-2875 2975);
DISPLAY 1.595745 (-2875 2975);
PAINT GREEN (-2875 2975);
DISPLAY INVISIBLE (-2875 2975);
FORCEPROP 1 LAST HDL_TAP TRUE
J 2
(-3200 2900);
DISPLAY 1.595745 (-3200 2900);
PAINT GREEN (-3200 2900);
DISPLAY INVISIBLE (-3200 2900);
FORCEPROP 1 LAST PATH I129
J 2
(-2873 3025);
DISPLAY 0.872340 (-2873 3025);
PAINT GREEN (-2873 3025);
DISPLAY INVISIBLE (-2873 3025);
FORCEADD TAP..6
(-5600 1075);
FORCEPROP 3 LASTPIN (-5550 1075) SIG_NAME M_H_ECC<0>
J 0
(-5540 1085);
DISPLAY 0.659574 (-5540 1085);
PAINT MONO (-5540 1085);
DISPLAY INVISIBLE (-5540 1085);
FORCEPROP 1 LASTPIN (-5550 1075) BN 0
J 0
(-5602 1083);
DISPLAY 0.617021 (-5602 1083);
PAINT GREEN (-5602 1083);
FORCEPROP 2 LAST CDS_LIB mstr_standard
J 0
(-5600 1075);
PAINT MONO (-5600 1075);
DISPLAY INVISIBLE (-5600 1075);
FORCEPROP 1 LAST BODY_TYPE PLUMBING
J 0
(-5600 1025);
DISPLAY 1.595745 (-5600 1025);
PAINT GREEN (-5600 1025);
DISPLAY INVISIBLE (-5600 1025);
FORCEPROP 1 LAST HDL_TAP TRUE
J 0
(-5275 950);
DISPLAY 1.595745 (-5275 950);
PAINT GREEN (-5275 950);
DISPLAY INVISIBLE (-5275 950);
FORCEPROP 1 LAST PATH I13
J 0
(-5602 1075);
DISPLAY 0.872340 (-5602 1075);
PAINT GREEN (-5602 1075);
DISPLAY INVISIBLE (-5602 1075);
FORCEADD TAP..6
R 2
(-2875 3125);
FORCEPROP 3 LASTPIN (-2925 3125) SIG_NAME M_H_DQS_DN<5>
J 0
(-2915 3135);
DISPLAY 0.659574 (-2915 3135);
PAINT MONO (-2915 3135);
DISPLAY INVISIBLE (-2915 3135);
FORCEPROP 1 LASTPIN (-2925 3125) BN 5
J 2
(-2873 3133);
DISPLAY 0.617021 (-2873 3133);
PAINT GREEN (-2873 3133);
FORCEPROP 2 LAST CDS_LIB mstr_standard
J 0
(-2875 3125);
PAINT MONO (-2875 3125);
DISPLAY INVISIBLE (-2875 3125);
FORCEPROP 1 LAST BODY_TYPE PLUMBING
J 2
(-2875 3075);
DISPLAY 1.595745 (-2875 3075);
PAINT GREEN (-2875 3075);
DISPLAY INVISIBLE (-2875 3075);
FORCEPROP 1 LAST HDL_TAP TRUE
J 2
(-3200 3000);
DISPLAY 1.595745 (-3200 3000);
PAINT GREEN (-3200 3000);
DISPLAY INVISIBLE (-3200 3000);
FORCEPROP 1 LAST PATH I130
J 2
(-2873 3125);
DISPLAY 0.872340 (-2873 3125);
PAINT GREEN (-2873 3125);
DISPLAY INVISIBLE (-2873 3125);
FORCEADD TAP..6
R 2
(-2875 3175);
FORCEPROP 3 LASTPIN (-2925 3175) SIG_NAME M_H_DQS_DN<6>
J 0
(-2915 3185);
DISPLAY 0.659574 (-2915 3185);
PAINT MONO (-2915 3185);
DISPLAY INVISIBLE (-2915 3185);
FORCEPROP 1 LASTPIN (-2925 3175) BN 6
J 2
(-2873 3183);
DISPLAY 0.617021 (-2873 3183);
PAINT GREEN (-2873 3183);
FORCEPROP 2 LAST CDS_LIB mstr_standard
J 0
(-2875 3175);
PAINT MONO (-2875 3175);
DISPLAY INVISIBLE (-2875 3175);
FORCEPROP 1 LAST BODY_TYPE PLUMBING
J 2
(-2875 3125);
DISPLAY 1.595745 (-2875 3125);
PAINT GREEN (-2875 3125);
DISPLAY INVISIBLE (-2875 3125);
FORCEPROP 1 LAST HDL_TAP TRUE
J 2
(-3200 3050);
DISPLAY 1.595745 (-3200 3050);
PAINT GREEN (-3200 3050);
DISPLAY INVISIBLE (-3200 3050);
FORCEPROP 1 LAST PATH I131
J 2
(-2873 3175);
DISPLAY 0.872340 (-2873 3175);
PAINT GREEN (-2873 3175);
DISPLAY INVISIBLE (-2873 3175);
FORCEADD TAP..6
R 2
(-2875 3225);
FORCEPROP 3 LASTPIN (-2925 3225) SIG_NAME M_H_DQS_DN<7>
J 0
(-2915 3235);
DISPLAY 0.659574 (-2915 3235);
PAINT MONO (-2915 3235);
DISPLAY INVISIBLE (-2915 3235);
FORCEPROP 1 LASTPIN (-2925 3225) BN 7
J 2
(-2873 3233);
DISPLAY 0.617021 (-2873 3233);
PAINT GREEN (-2873 3233);
FORCEPROP 2 LAST CDS_LIB mstr_standard
J 0
(-2875 3225);
PAINT MONO (-2875 3225);
DISPLAY INVISIBLE (-2875 3225);
FORCEPROP 1 LAST BODY_TYPE PLUMBING
J 2
(-2875 3175);
DISPLAY 1.595745 (-2875 3175);
PAINT GREEN (-2875 3175);
DISPLAY INVISIBLE (-2875 3175);
FORCEPROP 1 LAST HDL_TAP TRUE
J 2
(-3200 3100);
DISPLAY 1.595745 (-3200 3100);
PAINT GREEN (-3200 3100);
DISPLAY INVISIBLE (-3200 3100);
FORCEPROP 1 LAST PATH I132
J 2
(-2873 3225);
DISPLAY 0.872340 (-2873 3225);
PAINT GREEN (-2873 3225);
DISPLAY INVISIBLE (-2873 3225);
FORCEADD TAP..6
R 2
(-2875 3275);
FORCEPROP 3 LASTPIN (-2925 3275) SIG_NAME M_H_DQS_DN<8>
J 0
(-2915 3285);
DISPLAY 0.659574 (-2915 3285);
PAINT MONO (-2915 3285);
DISPLAY INVISIBLE (-2915 3285);
FORCEPROP 1 LASTPIN (-2925 3275) BN 8
J 2
(-2873 3283);
DISPLAY 0.617021 (-2873 3283);
PAINT GREEN (-2873 3283);
FORCEPROP 2 LAST CDS_LIB mstr_standard
J 0
(-2875 3275);
PAINT MONO (-2875 3275);
DISPLAY INVISIBLE (-2875 3275);
FORCEPROP 1 LAST BODY_TYPE PLUMBING
J 2
(-2875 3225);
DISPLAY 1.595745 (-2875 3225);
PAINT GREEN (-2875 3225);
DISPLAY INVISIBLE (-2875 3225);
FORCEPROP 1 LAST HDL_TAP TRUE
J 2
(-3200 3150);
DISPLAY 1.595745 (-3200 3150);
PAINT GREEN (-3200 3150);
DISPLAY INVISIBLE (-3200 3150);
FORCEPROP 1 LAST PATH I133
J 2
(-2873 3275);
DISPLAY 0.872340 (-2873 3275);
PAINT GREEN (-2873 3275);
DISPLAY INVISIBLE (-2873 3275);
FORCEADD TAP..6
R 2
(-2875 3325);
FORCEPROP 3 LASTPIN (-2925 3325) SIG_NAME M_H_DQS_DN<9>
J 0
(-2915 3335);
DISPLAY 0.659574 (-2915 3335);
PAINT MONO (-2915 3335);
DISPLAY INVISIBLE (-2915 3335);
FORCEPROP 1 LASTPIN (-2925 3325) BN 9
J 2
(-2873 3333);
DISPLAY 0.617021 (-2873 3333);
PAINT GREEN (-2873 3333);
FORCEPROP 2 LAST CDS_LIB mstr_standard
J 0
(-2875 3325);
PAINT MONO (-2875 3325);
DISPLAY INVISIBLE (-2875 3325);
FORCEPROP 1 LAST BODY_TYPE PLUMBING
J 2
(-2875 3275);
DISPLAY 1.595745 (-2875 3275);
PAINT GREEN (-2875 3275);
DISPLAY INVISIBLE (-2875 3275);
FORCEPROP 1 LAST HDL_TAP TRUE
J 2
(-3200 3200);
DISPLAY 1.595745 (-3200 3200);
PAINT GREEN (-3200 3200);
DISPLAY INVISIBLE (-3200 3200);
FORCEPROP 1 LAST PATH I134
J 2
(-2873 3325);
DISPLAY 0.872340 (-2873 3325);
PAINT GREEN (-2873 3325);
DISPLAY INVISIBLE (-2873 3325);
FORCEADD TAP..6
R 2
(-2875 3375);
FORCEPROP 3 LASTPIN (-2925 3375) SIG_NAME M_H_DQS_DN<10>
J 0
(-2915 3385);
DISPLAY 0.659574 (-2915 3385);
PAINT MONO (-2915 3385);
DISPLAY INVISIBLE (-2915 3385);
FORCEPROP 1 LASTPIN (-2925 3375) BN 10
J 2
(-2873 3383);
DISPLAY 0.617021 (-2873 3383);
PAINT GREEN (-2873 3383);
FORCEPROP 2 LAST CDS_LIB mstr_standard
J 0
(-2875 3375);
PAINT MONO (-2875 3375);
DISPLAY INVISIBLE (-2875 3375);
FORCEPROP 1 LAST BODY_TYPE PLUMBING
J 2
(-2875 3325);
DISPLAY 1.595745 (-2875 3325);
PAINT GREEN (-2875 3325);
DISPLAY INVISIBLE (-2875 3325);
FORCEPROP 1 LAST HDL_TAP TRUE
J 2
(-3200 3250);
DISPLAY 1.595745 (-3200 3250);
PAINT GREEN (-3200 3250);
DISPLAY INVISIBLE (-3200 3250);
FORCEPROP 1 LAST PATH I135
J 2
(-2873 3375);
DISPLAY 0.872340 (-2873 3375);
PAINT GREEN (-2873 3375);
DISPLAY INVISIBLE (-2873 3375);
FORCEADD TAP..6
R 2
(-2875 3475);
FORCEPROP 3 LASTPIN (-2925 3475) SIG_NAME M_H_DQS_DN<12>
J 0
(-2915 3485);
DISPLAY 0.659574 (-2915 3485);
PAINT MONO (-2915 3485);
DISPLAY INVISIBLE (-2915 3485);
FORCEPROP 1 LASTPIN (-2925 3475) BN 12
J 2
(-2873 3483);
DISPLAY 0.617021 (-2873 3483);
PAINT GREEN (-2873 3483);
FORCEPROP 2 LAST CDS_LIB mstr_standard
J 0
(-2875 3475);
PAINT MONO (-2875 3475);
DISPLAY INVISIBLE (-2875 3475);
FORCEPROP 1 LAST BODY_TYPE PLUMBING
J 2
(-2875 3425);
DISPLAY 1.595745 (-2875 3425);
PAINT GREEN (-2875 3425);
DISPLAY INVISIBLE (-2875 3425);
FORCEPROP 1 LAST HDL_TAP TRUE
J 2
(-3200 3350);
DISPLAY 1.595745 (-3200 3350);
PAINT GREEN (-3200 3350);
DISPLAY INVISIBLE (-3200 3350);
FORCEPROP 1 LAST PATH I136
J 2
(-2873 3475);
DISPLAY 0.872340 (-2873 3475);
PAINT GREEN (-2873 3475);
DISPLAY INVISIBLE (-2873 3475);
FORCEADD TAP..6
R 2
(-2875 3425);
FORCEPROP 3 LASTPIN (-2925 3425) SIG_NAME M_H_DQS_DN<11>
J 0
(-2915 3435);
DISPLAY 0.659574 (-2915 3435);
PAINT MONO (-2915 3435);
DISPLAY INVISIBLE (-2915 3435);
FORCEPROP 1 LASTPIN (-2925 3425) BN 11
J 2
(-2873 3433);
DISPLAY 0.617021 (-2873 3433);
PAINT GREEN (-2873 3433);
FORCEPROP 2 LAST CDS_LIB mstr_standard
J 0
(-2875 3425);
PAINT MONO (-2875 3425);
DISPLAY INVISIBLE (-2875 3425);
FORCEPROP 1 LAST BODY_TYPE PLUMBING
J 2
(-2875 3375);
DISPLAY 1.595745 (-2875 3375);
PAINT GREEN (-2875 3375);
DISPLAY INVISIBLE (-2875 3375);
FORCEPROP 1 LAST HDL_TAP TRUE
J 2
(-3200 3300);
DISPLAY 1.595745 (-3200 3300);
PAINT GREEN (-3200 3300);
DISPLAY INVISIBLE (-3200 3300);
FORCEPROP 1 LAST PATH I137
J 2
(-2873 3425);
DISPLAY 0.872340 (-2873 3425);
PAINT GREEN (-2873 3425);
DISPLAY INVISIBLE (-2873 3425);
FORCEADD TAP..6
R 2
(-2875 3625);
FORCEPROP 3 LASTPIN (-2925 3625) SIG_NAME M_H_DQS_DN<15>
J 0
(-2915 3635);
DISPLAY 0.659574 (-2915 3635);
PAINT MONO (-2915 3635);
DISPLAY INVISIBLE (-2915 3635);
FORCEPROP 1 LASTPIN (-2925 3625) BN 15
J 2
(-2873 3633);
DISPLAY 0.617021 (-2873 3633);
PAINT GREEN (-2873 3633);
FORCEPROP 2 LAST CDS_LIB mstr_standard
J 0
(-2875 3625);
PAINT MONO (-2875 3625);
DISPLAY INVISIBLE (-2875 3625);
FORCEPROP 1 LAST BODY_TYPE PLUMBING
J 2
(-2875 3575);
DISPLAY 1.595745 (-2875 3575);
PAINT GREEN (-2875 3575);
DISPLAY INVISIBLE (-2875 3575);
FORCEPROP 1 LAST HDL_TAP TRUE
J 2
(-3200 3500);
DISPLAY 1.595745 (-3200 3500);
PAINT GREEN (-3200 3500);
DISPLAY INVISIBLE (-3200 3500);
FORCEPROP 1 LAST PATH I138
J 2
(-2873 3625);
DISPLAY 0.872340 (-2873 3625);
PAINT GREEN (-2873 3625);
DISPLAY INVISIBLE (-2873 3625);
FORCEADD TAP..6
R 2
(-2875 3575);
FORCEPROP 3 LASTPIN (-2925 3575) SIG_NAME M_H_DQS_DN<14>
J 0
(-2915 3585);
DISPLAY 0.659574 (-2915 3585);
PAINT MONO (-2915 3585);
DISPLAY INVISIBLE (-2915 3585);
FORCEPROP 1 LASTPIN (-2925 3575) BN 14
J 2
(-2873 3583);
DISPLAY 0.617021 (-2873 3583);
PAINT GREEN (-2873 3583);
FORCEPROP 2 LAST CDS_LIB mstr_standard
J 0
(-2875 3575);
PAINT MONO (-2875 3575);
DISPLAY INVISIBLE (-2875 3575);
FORCEPROP 1 LAST BODY_TYPE PLUMBING
J 2
(-2875 3525);
DISPLAY 1.595745 (-2875 3525);
PAINT GREEN (-2875 3525);
DISPLAY INVISIBLE (-2875 3525);
FORCEPROP 1 LAST HDL_TAP TRUE
J 2
(-3200 3450);
DISPLAY 1.595745 (-3200 3450);
PAINT GREEN (-3200 3450);
DISPLAY INVISIBLE (-3200 3450);
FORCEPROP 1 LAST PATH I139
J 2
(-2873 3575);
DISPLAY 0.872340 (-2873 3575);
PAINT GREEN (-2873 3575);
DISPLAY INVISIBLE (-2873 3575);
FORCEADD TAP..6
(-5600 1125);
FORCEPROP 3 LASTPIN (-5550 1125) SIG_NAME M_H_ECC<1>
J 0
(-5540 1135);
DISPLAY 0.659574 (-5540 1135);
PAINT MONO (-5540 1135);
DISPLAY INVISIBLE (-5540 1135);
FORCEPROP 1 LASTPIN (-5550 1125) BN 1
J 0
(-5602 1133);
DISPLAY 0.617021 (-5602 1133);
PAINT GREEN (-5602 1133);
FORCEPROP 2 LAST CDS_LIB mstr_standard
J 0
(-5600 1125);
PAINT MONO (-5600 1125);
DISPLAY INVISIBLE (-5600 1125);
FORCEPROP 1 LAST BODY_TYPE PLUMBING
J 0
(-5600 1075);
DISPLAY 1.595745 (-5600 1075);
PAINT GREEN (-5600 1075);
DISPLAY INVISIBLE (-5600 1075);
FORCEPROP 1 LAST HDL_TAP TRUE
J 0
(-5275 1000);
DISPLAY 1.595745 (-5275 1000);
PAINT GREEN (-5275 1000);
DISPLAY INVISIBLE (-5275 1000);
FORCEPROP 1 LAST PATH I14
J 0
(-5602 1125);
DISPLAY 0.872340 (-5602 1125);
PAINT GREEN (-5602 1125);
DISPLAY INVISIBLE (-5602 1125);
FORCEADD TAP..6
R 2
(-2875 3525);
FORCEPROP 3 LASTPIN (-2925 3525) SIG_NAME M_H_DQS_DN<13>
J 0
(-2915 3535);
DISPLAY 0.659574 (-2915 3535);
PAINT MONO (-2915 3535);
DISPLAY INVISIBLE (-2915 3535);
FORCEPROP 1 LASTPIN (-2925 3525) BN 13
J 2
(-2873 3533);
DISPLAY 0.617021 (-2873 3533);
PAINT GREEN (-2873 3533);
FORCEPROP 2 LAST CDS_LIB mstr_standard
J 0
(-2875 3525);
PAINT MONO (-2875 3525);
DISPLAY INVISIBLE (-2875 3525);
FORCEPROP 1 LAST BODY_TYPE PLUMBING
J 2
(-2875 3475);
DISPLAY 1.595745 (-2875 3475);
PAINT GREEN (-2875 3475);
DISPLAY INVISIBLE (-2875 3475);
FORCEPROP 1 LAST HDL_TAP TRUE
J 2
(-3200 3400);
DISPLAY 1.595745 (-3200 3400);
PAINT GREEN (-3200 3400);
DISPLAY INVISIBLE (-3200 3400);
FORCEPROP 1 LAST PATH I140
J 2
(-2873 3525);
DISPLAY 0.872340 (-2873 3525);
PAINT GREEN (-2873 3525);
DISPLAY INVISIBLE (-2873 3525);
FORCEADD TAP..6
R 2
(-2875 3675);
FORCEPROP 3 LASTPIN (-2925 3675) SIG_NAME M_H_DQS_DN<16>
J 0
(-2915 3685);
DISPLAY 0.659574 (-2915 3685);
PAINT MONO (-2915 3685);
DISPLAY INVISIBLE (-2915 3685);
FORCEPROP 1 LASTPIN (-2925 3675) BN 16
J 2
(-2873 3683);
DISPLAY 0.617021 (-2873 3683);
PAINT GREEN (-2873 3683);
FORCEPROP 2 LAST CDS_LIB mstr_standard
J 0
(-2875 3675);
PAINT MONO (-2875 3675);
DISPLAY INVISIBLE (-2875 3675);
FORCEPROP 1 LAST BODY_TYPE PLUMBING
J 2
(-2875 3625);
DISPLAY 1.595745 (-2875 3625);
PAINT GREEN (-2875 3625);
DISPLAY INVISIBLE (-2875 3625);
FORCEPROP 1 LAST HDL_TAP TRUE
J 2
(-3200 3550);
DISPLAY 1.595745 (-3200 3550);
PAINT GREEN (-3200 3550);
DISPLAY INVISIBLE (-3200 3550);
FORCEPROP 1 LAST PATH I141
J 2
(-2873 3675);
DISPLAY 0.872340 (-2873 3675);
PAINT GREEN (-2873 3675);
DISPLAY INVISIBLE (-2873 3675);
FORCEADD TAP..6
R 2
(-2875 3725);
FORCEPROP 3 LASTPIN (-2925 3725) SIG_NAME M_H_DQS_DN<17>
J 0
(-2915 3735);
DISPLAY 0.659574 (-2915 3735);
PAINT MONO (-2915 3735);
DISPLAY INVISIBLE (-2915 3735);
FORCEPROP 1 LASTPIN (-2925 3725) BN 17
J 2
(-2873 3733);
DISPLAY 0.617021 (-2873 3733);
PAINT GREEN (-2873 3733);
FORCEPROP 2 LAST CDS_LIB mstr_standard
J 0
(-2875 3725);
PAINT MONO (-2875 3725);
DISPLAY INVISIBLE (-2875 3725);
FORCEPROP 1 LAST BODY_TYPE PLUMBING
J 2
(-2875 3675);
DISPLAY 1.595745 (-2875 3675);
PAINT GREEN (-2875 3675);
DISPLAY INVISIBLE (-2875 3675);
FORCEPROP 1 LAST HDL_TAP TRUE
J 2
(-3200 3600);
DISPLAY 1.595745 (-3200 3600);
PAINT GREEN (-3200 3600);
DISPLAY INVISIBLE (-3200 3600);
FORCEPROP 1 LAST PATH I142
J 2
(-2873 3725);
DISPLAY 0.872340 (-2873 3725);
PAINT GREEN (-2873 3725);
DISPLAY INVISIBLE (-2873 3725);
FORCEADD TAP..6
R 2
(-2875 3825);
FORCEPROP 3 LASTPIN (-2925 3825) SIG_NAME M_H_DQS_DP<0>
J 0
(-2915 3835);
DISPLAY 0.659574 (-2915 3835);
PAINT MONO (-2915 3835);
DISPLAY INVISIBLE (-2915 3835);
FORCEPROP 1 LASTPIN (-2925 3825) BN 0
J 2
(-2873 3833);
DISPLAY 0.617021 (-2873 3833);
PAINT GREEN (-2873 3833);
FORCEPROP 2 LAST CDS_LIB mstr_standard
J 0
(-2875 3825);
PAINT MONO (-2875 3825);
DISPLAY INVISIBLE (-2875 3825);
FORCEPROP 1 LAST BODY_TYPE PLUMBING
J 2
(-2875 3775);
DISPLAY 1.595745 (-2875 3775);
PAINT GREEN (-2875 3775);
DISPLAY INVISIBLE (-2875 3775);
FORCEPROP 1 LAST HDL_TAP TRUE
J 2
(-3200 3700);
DISPLAY 1.595745 (-3200 3700);
PAINT GREEN (-3200 3700);
DISPLAY INVISIBLE (-3200 3700);
FORCEPROP 1 LAST PATH I143
J 2
(-2873 3825);
DISPLAY 0.872340 (-2873 3825);
PAINT GREEN (-2873 3825);
DISPLAY INVISIBLE (-2873 3825);
FORCEADD TAP..6
R 2
(-2875 3875);
FORCEPROP 3 LASTPIN (-2925 3875) SIG_NAME M_H_DQS_DP<1>
J 0
(-2915 3885);
DISPLAY 0.659574 (-2915 3885);
PAINT MONO (-2915 3885);
DISPLAY INVISIBLE (-2915 3885);
FORCEPROP 1 LASTPIN (-2925 3875) BN 1
J 2
(-2873 3883);
DISPLAY 0.617021 (-2873 3883);
PAINT GREEN (-2873 3883);
FORCEPROP 2 LAST CDS_LIB mstr_standard
J 0
(-2875 3875);
PAINT MONO (-2875 3875);
DISPLAY INVISIBLE (-2875 3875);
FORCEPROP 1 LAST BODY_TYPE PLUMBING
J 2
(-2875 3825);
DISPLAY 1.595745 (-2875 3825);
PAINT GREEN (-2875 3825);
DISPLAY INVISIBLE (-2875 3825);
FORCEPROP 1 LAST HDL_TAP TRUE
J 2
(-3200 3750);
DISPLAY 1.595745 (-3200 3750);
PAINT GREEN (-3200 3750);
DISPLAY INVISIBLE (-3200 3750);
FORCEPROP 1 LAST PATH I144
J 2
(-2873 3875);
DISPLAY 0.872340 (-2873 3875);
PAINT GREEN (-2873 3875);
DISPLAY INVISIBLE (-2873 3875);
FORCEADD TAP..6
R 2
(-2875 3925);
FORCEPROP 3 LASTPIN (-2925 3925) SIG_NAME M_H_DQS_DP<2>
J 0
(-2915 3935);
DISPLAY 0.659574 (-2915 3935);
PAINT MONO (-2915 3935);
DISPLAY INVISIBLE (-2915 3935);
FORCEPROP 1 LASTPIN (-2925 3925) BN 2
J 2
(-2873 3933);
DISPLAY 0.617021 (-2873 3933);
PAINT GREEN (-2873 3933);
FORCEPROP 2 LAST CDS_LIB mstr_standard
J 0
(-2875 3925);
PAINT MONO (-2875 3925);
DISPLAY INVISIBLE (-2875 3925);
FORCEPROP 1 LAST BODY_TYPE PLUMBING
J 2
(-2875 3875);
DISPLAY 1.595745 (-2875 3875);
PAINT GREEN (-2875 3875);
DISPLAY INVISIBLE (-2875 3875);
FORCEPROP 1 LAST HDL_TAP TRUE
J 2
(-3200 3800);
DISPLAY 1.595745 (-3200 3800);
PAINT GREEN (-3200 3800);
DISPLAY INVISIBLE (-3200 3800);
FORCEPROP 1 LAST PATH I145
J 2
(-2873 3925);
DISPLAY 0.872340 (-2873 3925);
PAINT GREEN (-2873 3925);
DISPLAY INVISIBLE (-2873 3925);
FORCEADD TAP..6
R 2
(-2875 3975);
FORCEPROP 3 LASTPIN (-2925 3975) SIG_NAME M_H_DQS_DP<3>
J 0
(-2915 3985);
DISPLAY 0.659574 (-2915 3985);
PAINT MONO (-2915 3985);
DISPLAY INVISIBLE (-2915 3985);
FORCEPROP 1 LASTPIN (-2925 3975) BN 3
J 2
(-2873 3983);
DISPLAY 0.617021 (-2873 3983);
PAINT GREEN (-2873 3983);
FORCEPROP 2 LAST CDS_LIB mstr_standard
J 0
(-2875 3975);
PAINT MONO (-2875 3975);
DISPLAY INVISIBLE (-2875 3975);
FORCEPROP 1 LAST BODY_TYPE PLUMBING
J 2
(-2875 3925);
DISPLAY 1.595745 (-2875 3925);
PAINT GREEN (-2875 3925);
DISPLAY INVISIBLE (-2875 3925);
FORCEPROP 1 LAST HDL_TAP TRUE
J 2
(-3200 3850);
DISPLAY 1.595745 (-3200 3850);
PAINT GREEN (-3200 3850);
DISPLAY INVISIBLE (-3200 3850);
FORCEPROP 1 LAST PATH I146
J 2
(-2873 3975);
DISPLAY 0.872340 (-2873 3975);
PAINT GREEN (-2873 3975);
DISPLAY INVISIBLE (-2873 3975);
FORCEADD OFFPAGE..2
(-2025 525);
FORCEPROP 2 LAST $XR0 79 
J 0
(-1836 525);
DISPLAY 0.638298 (-1836 525);
PAINT MONO (-1836 525);
FORCEPROP 2 LAST $XR1 80 
J 0
(-1746 525);
DISPLAY 0.638298 (-1746 525);
PAINT MONO (-1746 525);
FORCEPROP 2 LAST CDS_LIB mstr_standard
J 0
(-2025 525);
PAINT MONO (-2025 525);
DISPLAY INVISIBLE (-2025 525);
FORCEPROP 1 LAST OFFPAGE TRUE
J 0
(-1700 400);
DISPLAY 1.170213 (-1700 400);
PAINT GREEN (-1700 400);
DISPLAY INVISIBLE (-1700 400);
FORCEPROP 1 LAST COMMENT_BODY TRUE
J 0
(-2070 430);
DISPLAY 1.170213 (-2070 430);
PAINT GREEN (-2070 430);
DISPLAY INVISIBLE (-2070 430);
FORCEPROP 2 LAST PATH I147
J 0
(-1850 600);
DISPLAY 1.021277 (-1850 600);
PAINT ORANGE (-1850 600);
DISPLAY INVISIBLE (-1850 600);
FORCEADD OFFPAGE..4
(-2025 575);
FORCEPROP 2 LAST $XR0 79 
J 0
(-1839 575);
DISPLAY 0.638298 (-1839 575);
PAINT MONO (-1839 575);
FORCEPROP 2 LAST $XR1 80 
J 0
(-1749 575);
DISPLAY 0.638298 (-1749 575);
PAINT MONO (-1749 575);
FORCEPROP 2 LAST CDS_LIB mstr_standard
J 0
(-2025 575);
PAINT MONO (-2025 575);
DISPLAY INVISIBLE (-2025 575);
FORCEPROP 1 LAST OFFPAGE TRUE
J 0
(-1700 450);
DISPLAY 1.170213 (-1700 450);
PAINT GREEN (-1700 450);
DISPLAY INVISIBLE (-1700 450);
FORCEPROP 1 LAST COMMENT_BODY TRUE
J 0
(-2050 475);
DISPLAY 1.170213 (-2050 475);
PAINT GREEN (-2050 475);
DISPLAY INVISIBLE (-2050 475);
FORCEPROP 2 LAST PATH I148
J 0
(-1850 650);
DISPLAY 1.021277 (-1850 650);
PAINT ORANGE (-1850 650);
DISPLAY INVISIBLE (-1850 650);
FORCEADD OFFPAGE..2
(-2025 625);
FORCEPROP 2 LAST $XR0 79 
J 0
(-1836 625);
DISPLAY 0.638298 (-1836 625);
PAINT MONO (-1836 625);
FORCEPROP 2 LAST $XR1 80 
J 0
(-1746 625);
DISPLAY 0.638298 (-1746 625);
PAINT MONO (-1746 625);
FORCEPROP 2 LAST CDS_LIB mstr_standard
J 0
(-2025 625);
PAINT MONO (-2025 625);
DISPLAY INVISIBLE (-2025 625);
FORCEPROP 1 LAST OFFPAGE TRUE
J 0
(-1700 500);
DISPLAY 1.170213 (-1700 500);
PAINT GREEN (-1700 500);
DISPLAY INVISIBLE (-1700 500);
FORCEPROP 1 LAST COMMENT_BODY TRUE
J 0
(-2070 530);
DISPLAY 1.170213 (-2070 530);
PAINT GREEN (-2070 530);
DISPLAY INVISIBLE (-2070 530);
FORCEPROP 2 LAST PATH I149
J 0
(-1850 700);
DISPLAY 1.021277 (-1850 700);
PAINT ORANGE (-1850 700);
DISPLAY INVISIBLE (-1850 700);
FORCEADD TAP..6
(-5600 1175);
FORCEPROP 3 LASTPIN (-5550 1175) SIG_NAME M_H_ECC<2>
J 0
(-5540 1185);
DISPLAY 0.659574 (-5540 1185);
PAINT MONO (-5540 1185);
DISPLAY INVISIBLE (-5540 1185);
FORCEPROP 1 LASTPIN (-5550 1175) BN 2
J 0
(-5602 1183);
DISPLAY 0.617021 (-5602 1183);
PAINT GREEN (-5602 1183);
FORCEPROP 2 LAST CDS_LIB mstr_standard
J 0
(-5600 1175);
PAINT MONO (-5600 1175);
DISPLAY INVISIBLE (-5600 1175);
FORCEPROP 1 LAST BODY_TYPE PLUMBING
J 0
(-5600 1125);
DISPLAY 1.595745 (-5600 1125);
PAINT GREEN (-5600 1125);
DISPLAY INVISIBLE (-5600 1125);
FORCEPROP 1 LAST HDL_TAP TRUE
J 0
(-5275 1050);
DISPLAY 1.595745 (-5275 1050);
PAINT GREEN (-5275 1050);
DISPLAY INVISIBLE (-5275 1050);
FORCEPROP 1 LAST PATH I15
J 0
(-5602 1175);
DISPLAY 0.872340 (-5602 1175);
PAINT GREEN (-5602 1175);
DISPLAY INVISIBLE (-5602 1175);
FORCEADD OFFPAGE..2
(-2025 825);
FORCEPROP 2 LAST $XR0 79 
J 0
(-1836 825);
DISPLAY 0.638298 (-1836 825);
PAINT MONO (-1836 825);
FORCEPROP 2 LAST $XR1 80 
J 0
(-1746 825);
DISPLAY 0.638298 (-1746 825);
PAINT MONO (-1746 825);
FORCEPROP 2 LAST CDS_LIB mstr_standard
J 0
(-2025 825);
PAINT MONO (-2025 825);
DISPLAY INVISIBLE (-2025 825);
FORCEPROP 1 LAST OFFPAGE TRUE
J 0
(-1700 700);
DISPLAY 1.170213 (-1700 700);
PAINT GREEN (-1700 700);
DISPLAY INVISIBLE (-1700 700);
FORCEPROP 1 LAST COMMENT_BODY TRUE
J 0
(-2070 730);
DISPLAY 1.170213 (-2070 730);
PAINT GREEN (-2070 730);
DISPLAY INVISIBLE (-2070 730);
FORCEPROP 2 LAST PATH I150
J 0
(-1850 900);
DISPLAY 1.021277 (-1850 900);
PAINT ORANGE (-1850 900);
DISPLAY INVISIBLE (-1850 900);
FORCEADD OFFPAGE..2
(-2025 925);
FORCEPROP 2 LAST $XR0 79 
J 0
(-1836 925);
DISPLAY 0.638298 (-1836 925);
PAINT MONO (-1836 925);
FORCEPROP 2 LAST $XR1 80 
J 0
(-1746 925);
DISPLAY 0.638298 (-1746 925);
PAINT MONO (-1746 925);
FORCEPROP 2 LAST CDS_LIB mstr_standard
J 0
(-2025 925);
PAINT MONO (-2025 925);
DISPLAY INVISIBLE (-2025 925);
FORCEPROP 1 LAST OFFPAGE TRUE
J 0
(-1700 800);
DISPLAY 1.170213 (-1700 800);
PAINT GREEN (-1700 800);
DISPLAY INVISIBLE (-1700 800);
FORCEPROP 1 LAST COMMENT_BODY TRUE
J 0
(-2070 830);
DISPLAY 1.170213 (-2070 830);
PAINT GREEN (-2070 830);
DISPLAY INVISIBLE (-2070 830);
FORCEPROP 2 LAST PATH I151
J 0
(-1850 1000);
DISPLAY 1.021277 (-1850 1000);
PAINT ORANGE (-1850 1000);
DISPLAY INVISIBLE (-1850 1000);
FORCEADD OFFPAGE..2
(-2025 1375);
FORCEPROP 2 LAST $XR0 79 
J 0
(-1836 1375);
DISPLAY 0.638298 (-1836 1375);
PAINT MONO (-1836 1375);
FORCEPROP 2 LAST $XR1 80 
J 0
(-1746 1375);
DISPLAY 0.638298 (-1746 1375);
PAINT MONO (-1746 1375);
FORCEPROP 2 LAST CDS_LIB mstr_standard
J 0
(-2025 1375);
PAINT MONO (-2025 1375);
DISPLAY INVISIBLE (-2025 1375);
FORCEPROP 1 LAST OFFPAGE TRUE
J 0
(-1700 1250);
DISPLAY 1.170213 (-1700 1250);
PAINT GREEN (-1700 1250);
DISPLAY INVISIBLE (-1700 1250);
FORCEPROP 1 LAST COMMENT_BODY TRUE
J 0
(-2070 1280);
DISPLAY 1.170213 (-2070 1280);
PAINT GREEN (-2070 1280);
DISPLAY INVISIBLE (-2070 1280);
FORCEPROP 2 LAST PATH I152
J 0
(-1850 1450);
DISPLAY 1.021277 (-1850 1450);
PAINT ORANGE (-1850 1450);
DISPLAY INVISIBLE (-1850 1450);
FORCEADD OFFPAGE..2
(-2025 1625);
FORCEPROP 2 LAST $XR0 79 
J 0
(-1836 1625);
DISPLAY 0.638298 (-1836 1625);
PAINT MONO (-1836 1625);
FORCEPROP 2 LAST $XR1 80 
J 0
(-1746 1625);
DISPLAY 0.638298 (-1746 1625);
PAINT MONO (-1746 1625);
FORCEPROP 2 LAST CDS_LIB mstr_standard
J 0
(-2025 1625);
PAINT MONO (-2025 1625);
DISPLAY INVISIBLE (-2025 1625);
FORCEPROP 1 LAST OFFPAGE TRUE
J 0
(-1700 1500);
DISPLAY 1.170213 (-1700 1500);
PAINT GREEN (-1700 1500);
DISPLAY INVISIBLE (-1700 1500);
FORCEPROP 1 LAST COMMENT_BODY TRUE
J 0
(-2070 1530);
DISPLAY 1.170213 (-2070 1530);
PAINT GREEN (-2070 1530);
DISPLAY INVISIBLE (-2070 1530);
FORCEPROP 2 LAST PATH I153
J 0
(-1850 1700);
DISPLAY 1.021277 (-1850 1700);
PAINT ORANGE (-1850 1700);
DISPLAY INVISIBLE (-1850 1700);
FORCEADD OFFPAGE..2
(-2025 1875);
FORCEPROP 2 LAST $XR0 79 
J 0
(-1836 1875);
DISPLAY 0.638298 (-1836 1875);
PAINT MONO (-1836 1875);
FORCEPROP 2 LAST $XR1 80 
J 0
(-1746 1875);
DISPLAY 0.638298 (-1746 1875);
PAINT MONO (-1746 1875);
FORCEPROP 2 LAST CDS_LIB mstr_standard
J 0
(-2025 1875);
PAINT MONO (-2025 1875);
DISPLAY INVISIBLE (-2025 1875);
FORCEPROP 1 LAST OFFPAGE TRUE
J 0
(-1700 1750);
DISPLAY 1.170213 (-1700 1750);
PAINT GREEN (-1700 1750);
DISPLAY INVISIBLE (-1700 1750);
FORCEPROP 1 LAST COMMENT_BODY TRUE
J 0
(-2070 1780);
DISPLAY 1.170213 (-2070 1780);
PAINT GREEN (-2070 1780);
DISPLAY INVISIBLE (-2070 1780);
FORCEPROP 2 LAST PATH I154
J 0
(-1850 1950);
DISPLAY 1.021277 (-1850 1950);
PAINT ORANGE (-1850 1950);
DISPLAY INVISIBLE (-1850 1950);
FORCEADD OFFPAGE..2
(-2025 2825);
FORCEPROP 2 LAST $XR0 79 
J 0
(-1836 2825);
DISPLAY 0.638298 (-1836 2825);
PAINT MONO (-1836 2825);
FORCEPROP 2 LAST $XR1 80 
J 0
(-1746 2825);
DISPLAY 0.638298 (-1746 2825);
PAINT MONO (-1746 2825);
FORCEPROP 2 LAST CDS_LIB mstr_standard
J 0
(-2025 2825);
PAINT MONO (-2025 2825);
DISPLAY INVISIBLE (-2025 2825);
FORCEPROP 1 LAST OFFPAGE TRUE
J 0
(-1700 2700);
DISPLAY 1.170213 (-1700 2700);
PAINT GREEN (-1700 2700);
DISPLAY INVISIBLE (-1700 2700);
FORCEPROP 1 LAST COMMENT_BODY TRUE
J 0
(-2070 2730);
DISPLAY 1.170213 (-2070 2730);
PAINT GREEN (-2070 2730);
DISPLAY INVISIBLE (-2070 2730);
FORCEPROP 2 LAST PATH I155
J 0
(-1850 2900);
DISPLAY 1.021277 (-1850 2900);
PAINT ORANGE (-1850 2900);
DISPLAY INVISIBLE (-1850 2900);
FORCEADD OFFPAGE..3
(-2025 3775);
FORCEPROP 2 LAST $XR0 79 
J 0
(-1811 3775);
DISPLAY 0.638298 (-1811 3775);
PAINT MONO (-1811 3775);
FORCEPROP 2 LAST $XR1 80 
J 0
(-1721 3775);
DISPLAY 0.638298 (-1721 3775);
PAINT MONO (-1721 3775);
FORCEPROP 2 LAST CDS_LIB mstr_standard
J 0
(-2025 3775);
PAINT MONO (-2025 3775);
DISPLAY INVISIBLE (-2025 3775);
FORCEPROP 1 LAST OFFPAGE TRUE
J 0
(-1700 3650);
DISPLAY 1.170213 (-1700 3650);
PAINT GREEN (-1700 3650);
DISPLAY INVISIBLE (-1700 3650);
FORCEPROP 1 LAST COMMENT_BODY TRUE
J 0
(-2075 3675);
DISPLAY 1.170213 (-2075 3675);
PAINT GREEN (-2075 3675);
DISPLAY INVISIBLE (-2075 3675);
FORCEPROP 2 LAST PATH I156
J 0
(-1825 3850);
DISPLAY 1.021277 (-1825 3850);
PAINT ORANGE (-1825 3850);
DISPLAY INVISIBLE (-1825 3850);
FORCEADD TAP..6
R 2
(-2875 4025);
FORCEPROP 3 LASTPIN (-2925 4025) SIG_NAME M_H_DQS_DP<4>
J 0
(-2915 4035);
DISPLAY 0.659574 (-2915 4035);
PAINT MONO (-2915 4035);
DISPLAY INVISIBLE (-2915 4035);
FORCEPROP 1 LASTPIN (-2925 4025) BN 4
J 2
(-2873 4033);
DISPLAY 0.617021 (-2873 4033);
PAINT GREEN (-2873 4033);
FORCEPROP 2 LAST CDS_LIB mstr_standard
J 0
(-2875 4025);
PAINT MONO (-2875 4025);
DISPLAY INVISIBLE (-2875 4025);
FORCEPROP 1 LAST BODY_TYPE PLUMBING
J 2
(-2875 3975);
DISPLAY 1.595745 (-2875 3975);
PAINT GREEN (-2875 3975);
DISPLAY INVISIBLE (-2875 3975);
FORCEPROP 1 LAST HDL_TAP TRUE
J 2
(-3200 3900);
DISPLAY 1.595745 (-3200 3900);
PAINT GREEN (-3200 3900);
DISPLAY INVISIBLE (-3200 3900);
FORCEPROP 1 LAST PATH I157
J 2
(-2873 4025);
DISPLAY 0.872340 (-2873 4025);
PAINT GREEN (-2873 4025);
DISPLAY INVISIBLE (-2873 4025);
FORCEADD TAP..6
R 2
(-2875 4125);
FORCEPROP 3 LASTPIN (-2925 4125) SIG_NAME M_H_DQS_DP<6>
J 0
(-2915 4135);
DISPLAY 0.659574 (-2915 4135);
PAINT MONO (-2915 4135);
DISPLAY INVISIBLE (-2915 4135);
FORCEPROP 1 LASTPIN (-2925 4125) BN 6
J 2
(-2873 4133);
DISPLAY 0.617021 (-2873 4133);
PAINT GREEN (-2873 4133);
FORCEPROP 2 LAST CDS_LIB mstr_standard
J 0
(-2875 4125);
PAINT MONO (-2875 4125);
DISPLAY INVISIBLE (-2875 4125);
FORCEPROP 1 LAST BODY_TYPE PLUMBING
J 2
(-2875 4075);
DISPLAY 1.595745 (-2875 4075);
PAINT GREEN (-2875 4075);
DISPLAY INVISIBLE (-2875 4075);
FORCEPROP 1 LAST HDL_TAP TRUE
J 2
(-3200 4000);
DISPLAY 1.595745 (-3200 4000);
PAINT GREEN (-3200 4000);
DISPLAY INVISIBLE (-3200 4000);
FORCEPROP 1 LAST PATH I158
J 2
(-2873 4125);
DISPLAY 0.872340 (-2873 4125);
PAINT GREEN (-2873 4125);
DISPLAY INVISIBLE (-2873 4125);
FORCEADD TAP..6
R 2
(-2875 4075);
FORCEPROP 3 LASTPIN (-2925 4075) SIG_NAME M_H_DQS_DP<5>
J 0
(-2915 4085);
DISPLAY 0.659574 (-2915 4085);
PAINT MONO (-2915 4085);
DISPLAY INVISIBLE (-2915 4085);
FORCEPROP 1 LASTPIN (-2925 4075) BN 5
J 2
(-2873 4083);
DISPLAY 0.617021 (-2873 4083);
PAINT GREEN (-2873 4083);
FORCEPROP 2 LAST CDS_LIB mstr_standard
J 0
(-2875 4075);
PAINT MONO (-2875 4075);
DISPLAY INVISIBLE (-2875 4075);
FORCEPROP 1 LAST BODY_TYPE PLUMBING
J 2
(-2875 4025);
DISPLAY 1.595745 (-2875 4025);
PAINT GREEN (-2875 4025);
DISPLAY INVISIBLE (-2875 4025);
FORCEPROP 1 LAST HDL_TAP TRUE
J 2
(-3200 3950);
DISPLAY 1.595745 (-3200 3950);
PAINT GREEN (-3200 3950);
DISPLAY INVISIBLE (-3200 3950);
FORCEPROP 1 LAST PATH I159
J 2
(-2873 4075);
DISPLAY 0.872340 (-2873 4075);
PAINT GREEN (-2873 4075);
DISPLAY INVISIBLE (-2873 4075);
FORCEADD TAP..6
(-5600 1275);
FORCEPROP 3 LASTPIN (-5550 1275) SIG_NAME M_H_ECC<4>
J 0
(-5540 1285);
DISPLAY 0.659574 (-5540 1285);
PAINT MONO (-5540 1285);
DISPLAY INVISIBLE (-5540 1285);
FORCEPROP 1 LASTPIN (-5550 1275) BN 4
J 0
(-5602 1283);
DISPLAY 0.617021 (-5602 1283);
PAINT GREEN (-5602 1283);
FORCEPROP 2 LAST CDS_LIB mstr_standard
J 0
(-5600 1275);
PAINT MONO (-5600 1275);
DISPLAY INVISIBLE (-5600 1275);
FORCEPROP 1 LAST BODY_TYPE PLUMBING
J 0
(-5600 1225);
DISPLAY 1.595745 (-5600 1225);
PAINT GREEN (-5600 1225);
DISPLAY INVISIBLE (-5600 1225);
FORCEPROP 1 LAST HDL_TAP TRUE
J 0
(-5275 1150);
DISPLAY 1.595745 (-5275 1150);
PAINT GREEN (-5275 1150);
DISPLAY INVISIBLE (-5275 1150);
FORCEPROP 1 LAST PATH I16
J 0
(-5602 1275);
DISPLAY 0.872340 (-5602 1275);
PAINT GREEN (-5602 1275);
DISPLAY INVISIBLE (-5602 1275);
FORCEADD TAP..6
R 2
(-2875 4175);
FORCEPROP 3 LASTPIN (-2925 4175) SIG_NAME M_H_DQS_DP<7>
J 0
(-2915 4185);
DISPLAY 0.659574 (-2915 4185);
PAINT MONO (-2915 4185);
DISPLAY INVISIBLE (-2915 4185);
FORCEPROP 1 LASTPIN (-2925 4175) BN 7
J 2
(-2873 4183);
DISPLAY 0.617021 (-2873 4183);
PAINT GREEN (-2873 4183);
FORCEPROP 2 LAST CDS_LIB mstr_standard
J 0
(-2875 4175);
PAINT MONO (-2875 4175);
DISPLAY INVISIBLE (-2875 4175);
FORCEPROP 1 LAST BODY_TYPE PLUMBING
J 2
(-2875 4125);
DISPLAY 1.595745 (-2875 4125);
PAINT GREEN (-2875 4125);
DISPLAY INVISIBLE (-2875 4125);
FORCEPROP 1 LAST HDL_TAP TRUE
J 2
(-3200 4050);
DISPLAY 1.595745 (-3200 4050);
PAINT GREEN (-3200 4050);
DISPLAY INVISIBLE (-3200 4050);
FORCEPROP 1 LAST PATH I160
J 2
(-2873 4175);
DISPLAY 0.872340 (-2873 4175);
PAINT GREEN (-2873 4175);
DISPLAY INVISIBLE (-2873 4175);
FORCEADD TAP..6
R 2
(-2875 4225);
FORCEPROP 3 LASTPIN (-2925 4225) SIG_NAME M_H_DQS_DP<8>
J 0
(-2915 4235);
DISPLAY 0.659574 (-2915 4235);
PAINT MONO (-2915 4235);
DISPLAY INVISIBLE (-2915 4235);
FORCEPROP 1 LASTPIN (-2925 4225) BN 8
J 2
(-2873 4233);
DISPLAY 0.617021 (-2873 4233);
PAINT GREEN (-2873 4233);
FORCEPROP 2 LAST CDS_LIB mstr_standard
J 0
(-2875 4225);
PAINT MONO (-2875 4225);
DISPLAY INVISIBLE (-2875 4225);
FORCEPROP 1 LAST BODY_TYPE PLUMBING
J 2
(-2875 4175);
DISPLAY 1.595745 (-2875 4175);
PAINT GREEN (-2875 4175);
DISPLAY INVISIBLE (-2875 4175);
FORCEPROP 1 LAST HDL_TAP TRUE
J 2
(-3200 4100);
DISPLAY 1.595745 (-3200 4100);
PAINT GREEN (-3200 4100);
DISPLAY INVISIBLE (-3200 4100);
FORCEPROP 1 LAST PATH I161
J 2
(-2873 4225);
DISPLAY 0.872340 (-2873 4225);
PAINT GREEN (-2873 4225);
DISPLAY INVISIBLE (-2873 4225);
FORCEADD TAP..6
R 2
(-2875 4275);
FORCEPROP 3 LASTPIN (-2925 4275) SIG_NAME M_H_DQS_DP<9>
J 0
(-2915 4285);
DISPLAY 0.659574 (-2915 4285);
PAINT MONO (-2915 4285);
DISPLAY INVISIBLE (-2915 4285);
FORCEPROP 1 LASTPIN (-2925 4275) BN 9
J 2
(-2873 4283);
DISPLAY 0.617021 (-2873 4283);
PAINT GREEN (-2873 4283);
FORCEPROP 2 LAST CDS_LIB mstr_standard
J 0
(-2875 4275);
PAINT MONO (-2875 4275);
DISPLAY INVISIBLE (-2875 4275);
FORCEPROP 1 LAST BODY_TYPE PLUMBING
J 2
(-2875 4225);
DISPLAY 1.595745 (-2875 4225);
PAINT GREEN (-2875 4225);
DISPLAY INVISIBLE (-2875 4225);
FORCEPROP 1 LAST HDL_TAP TRUE
J 2
(-3200 4150);
DISPLAY 1.595745 (-3200 4150);
PAINT GREEN (-3200 4150);
DISPLAY INVISIBLE (-3200 4150);
FORCEPROP 1 LAST PATH I162
J 2
(-2873 4275);
DISPLAY 0.872340 (-2873 4275);
PAINT GREEN (-2873 4275);
DISPLAY INVISIBLE (-2873 4275);
FORCEADD TAP..6
R 2
(-2875 4325);
FORCEPROP 3 LASTPIN (-2925 4325) SIG_NAME M_H_DQS_DP<10>
J 0
(-2915 4335);
DISPLAY 0.659574 (-2915 4335);
PAINT MONO (-2915 4335);
DISPLAY INVISIBLE (-2915 4335);
FORCEPROP 1 LASTPIN (-2925 4325) BN 10
J 2
(-2873 4333);
DISPLAY 0.617021 (-2873 4333);
PAINT GREEN (-2873 4333);
FORCEPROP 2 LAST CDS_LIB mstr_standard
J 0
(-2875 4325);
PAINT MONO (-2875 4325);
DISPLAY INVISIBLE (-2875 4325);
FORCEPROP 1 LAST BODY_TYPE PLUMBING
J 2
(-2875 4275);
DISPLAY 1.595745 (-2875 4275);
PAINT GREEN (-2875 4275);
DISPLAY INVISIBLE (-2875 4275);
FORCEPROP 1 LAST HDL_TAP TRUE
J 2
(-3200 4200);
DISPLAY 1.595745 (-3200 4200);
PAINT GREEN (-3200 4200);
DISPLAY INVISIBLE (-3200 4200);
FORCEPROP 1 LAST PATH I163
J 2
(-2873 4325);
DISPLAY 0.872340 (-2873 4325);
PAINT GREEN (-2873 4325);
DISPLAY INVISIBLE (-2873 4325);
FORCEADD TAP..6
R 2
(-2875 4375);
FORCEPROP 3 LASTPIN (-2925 4375) SIG_NAME M_H_DQS_DP<11>
J 0
(-2915 4385);
DISPLAY 0.659574 (-2915 4385);
PAINT MONO (-2915 4385);
DISPLAY INVISIBLE (-2915 4385);
FORCEPROP 1 LASTPIN (-2925 4375) BN 11
J 2
(-2873 4383);
DISPLAY 0.617021 (-2873 4383);
PAINT GREEN (-2873 4383);
FORCEPROP 2 LAST CDS_LIB mstr_standard
J 0
(-2875 4375);
PAINT MONO (-2875 4375);
DISPLAY INVISIBLE (-2875 4375);
FORCEPROP 1 LAST BODY_TYPE PLUMBING
J 2
(-2875 4325);
DISPLAY 1.595745 (-2875 4325);
PAINT GREEN (-2875 4325);
DISPLAY INVISIBLE (-2875 4325);
FORCEPROP 1 LAST HDL_TAP TRUE
J 2
(-3200 4250);
DISPLAY 1.595745 (-3200 4250);
PAINT GREEN (-3200 4250);
DISPLAY INVISIBLE (-3200 4250);
FORCEPROP 1 LAST PATH I164
J 2
(-2873 4375);
DISPLAY 0.872340 (-2873 4375);
PAINT GREEN (-2873 4375);
DISPLAY INVISIBLE (-2873 4375);
FORCEADD TAP..6
R 2
(-2875 4525);
FORCEPROP 3 LASTPIN (-2925 4525) SIG_NAME M_H_DQS_DP<14>
J 0
(-2915 4535);
DISPLAY 0.659574 (-2915 4535);
PAINT MONO (-2915 4535);
DISPLAY INVISIBLE (-2915 4535);
FORCEPROP 1 LASTPIN (-2925 4525) BN 14
J 2
(-2873 4533);
DISPLAY 0.617021 (-2873 4533);
PAINT GREEN (-2873 4533);
FORCEPROP 2 LAST CDS_LIB mstr_standard
J 0
(-2875 4525);
PAINT MONO (-2875 4525);
DISPLAY INVISIBLE (-2875 4525);
FORCEPROP 1 LAST BODY_TYPE PLUMBING
J 2
(-2875 4475);
DISPLAY 1.595745 (-2875 4475);
PAINT GREEN (-2875 4475);
DISPLAY INVISIBLE (-2875 4475);
FORCEPROP 1 LAST HDL_TAP TRUE
J 2
(-3200 4400);
DISPLAY 1.595745 (-3200 4400);
PAINT GREEN (-3200 4400);
DISPLAY INVISIBLE (-3200 4400);
FORCEPROP 1 LAST PATH I165
J 2
(-2873 4525);
DISPLAY 0.872340 (-2873 4525);
PAINT GREEN (-2873 4525);
DISPLAY INVISIBLE (-2873 4525);
FORCEADD TAP..6
R 2
(-2875 4475);
FORCEPROP 3 LASTPIN (-2925 4475) SIG_NAME M_H_DQS_DP<13>
J 0
(-2915 4485);
DISPLAY 0.659574 (-2915 4485);
PAINT MONO (-2915 4485);
DISPLAY INVISIBLE (-2915 4485);
FORCEPROP 1 LASTPIN (-2925 4475) BN 13
J 2
(-2873 4483);
DISPLAY 0.617021 (-2873 4483);
PAINT GREEN (-2873 4483);
FORCEPROP 2 LAST CDS_LIB mstr_standard
J 0
(-2875 4475);
PAINT MONO (-2875 4475);
DISPLAY INVISIBLE (-2875 4475);
FORCEPROP 1 LAST BODY_TYPE PLUMBING
J 2
(-2875 4425);
DISPLAY 1.595745 (-2875 4425);
PAINT GREEN (-2875 4425);
DISPLAY INVISIBLE (-2875 4425);
FORCEPROP 1 LAST HDL_TAP TRUE
J 2
(-3200 4350);
DISPLAY 1.595745 (-3200 4350);
PAINT GREEN (-3200 4350);
DISPLAY INVISIBLE (-3200 4350);
FORCEPROP 1 LAST PATH I166
J 2
(-2873 4475);
DISPLAY 0.872340 (-2873 4475);
PAINT GREEN (-2873 4475);
DISPLAY INVISIBLE (-2873 4475);
FORCEADD TAP..6
R 2
(-2875 4425);
FORCEPROP 3 LASTPIN (-2925 4425) SIG_NAME M_H_DQS_DP<12>
J 0
(-2915 4435);
DISPLAY 0.659574 (-2915 4435);
PAINT MONO (-2915 4435);
DISPLAY INVISIBLE (-2915 4435);
FORCEPROP 1 LASTPIN (-2925 4425) BN 12
J 2
(-2873 4433);
DISPLAY 0.617021 (-2873 4433);
PAINT GREEN (-2873 4433);
FORCEPROP 2 LAST CDS_LIB mstr_standard
J 0
(-2875 4425);
PAINT MONO (-2875 4425);
DISPLAY INVISIBLE (-2875 4425);
FORCEPROP 1 LAST BODY_TYPE PLUMBING
J 2
(-2875 4375);
DISPLAY 1.595745 (-2875 4375);
PAINT GREEN (-2875 4375);
DISPLAY INVISIBLE (-2875 4375);
FORCEPROP 1 LAST HDL_TAP TRUE
J 2
(-3200 4300);
DISPLAY 1.595745 (-3200 4300);
PAINT GREEN (-3200 4300);
DISPLAY INVISIBLE (-3200 4300);
FORCEPROP 1 LAST PATH I167
J 2
(-2873 4425);
DISPLAY 0.872340 (-2873 4425);
PAINT GREEN (-2873 4425);
DISPLAY INVISIBLE (-2873 4425);
FORCEADD TAP..6
R 2
(-2875 4575);
FORCEPROP 3 LASTPIN (-2925 4575) SIG_NAME M_H_DQS_DP<15>
J 0
(-2915 4585);
DISPLAY 0.659574 (-2915 4585);
PAINT MONO (-2915 4585);
DISPLAY INVISIBLE (-2915 4585);
FORCEPROP 1 LASTPIN (-2925 4575) BN 15
J 2
(-2873 4583);
DISPLAY 0.617021 (-2873 4583);
PAINT GREEN (-2873 4583);
FORCEPROP 2 LAST CDS_LIB mstr_standard
J 0
(-2875 4575);
PAINT MONO (-2875 4575);
DISPLAY INVISIBLE (-2875 4575);
FORCEPROP 1 LAST BODY_TYPE PLUMBING
J 2
(-2875 4525);
DISPLAY 1.595745 (-2875 4525);
PAINT GREEN (-2875 4525);
DISPLAY INVISIBLE (-2875 4525);
FORCEPROP 1 LAST HDL_TAP TRUE
J 2
(-3200 4450);
DISPLAY 1.595745 (-3200 4450);
PAINT GREEN (-3200 4450);
DISPLAY INVISIBLE (-3200 4450);
FORCEPROP 1 LAST PATH I168
J 2
(-2873 4575);
DISPLAY 0.872340 (-2873 4575);
PAINT GREEN (-2873 4575);
DISPLAY INVISIBLE (-2873 4575);
FORCEADD TAP..6
R 2
(-2875 4625);
FORCEPROP 3 LASTPIN (-2925 4625) SIG_NAME M_H_DQS_DP<16>
J 0
(-2915 4635);
DISPLAY 0.659574 (-2915 4635);
PAINT MONO (-2915 4635);
DISPLAY INVISIBLE (-2915 4635);
FORCEPROP 1 LASTPIN (-2925 4625) BN 16
J 2
(-2873 4633);
DISPLAY 0.617021 (-2873 4633);
PAINT GREEN (-2873 4633);
FORCEPROP 2 LAST CDS_LIB mstr_standard
J 0
(-2875 4625);
PAINT MONO (-2875 4625);
DISPLAY INVISIBLE (-2875 4625);
FORCEPROP 1 LAST BODY_TYPE PLUMBING
J 2
(-2875 4575);
DISPLAY 1.595745 (-2875 4575);
PAINT GREEN (-2875 4575);
DISPLAY INVISIBLE (-2875 4575);
FORCEPROP 1 LAST HDL_TAP TRUE
J 2
(-3200 4500);
DISPLAY 1.595745 (-3200 4500);
PAINT GREEN (-3200 4500);
DISPLAY INVISIBLE (-3200 4500);
FORCEPROP 1 LAST PATH I169
J 2
(-2873 4625);
DISPLAY 0.872340 (-2873 4625);
PAINT GREEN (-2873 4625);
DISPLAY INVISIBLE (-2873 4625);
FORCEADD TAP..6
(-5600 1225);
FORCEPROP 3 LASTPIN (-5550 1225) SIG_NAME M_H_ECC<3>
J 0
(-5540 1235);
DISPLAY 0.659574 (-5540 1235);
PAINT MONO (-5540 1235);
DISPLAY INVISIBLE (-5540 1235);
FORCEPROP 1 LASTPIN (-5550 1225) BN 3
J 0
(-5602 1233);
DISPLAY 0.617021 (-5602 1233);
PAINT GREEN (-5602 1233);
FORCEPROP 2 LAST CDS_LIB mstr_standard
J 0
(-5600 1225);
PAINT MONO (-5600 1225);
DISPLAY INVISIBLE (-5600 1225);
FORCEPROP 1 LAST BODY_TYPE PLUMBING
J 0
(-5600 1175);
DISPLAY 1.595745 (-5600 1175);
PAINT GREEN (-5600 1175);
DISPLAY INVISIBLE (-5600 1175);
FORCEPROP 1 LAST HDL_TAP TRUE
J 0
(-5275 1100);
DISPLAY 1.595745 (-5275 1100);
PAINT GREEN (-5275 1100);
DISPLAY INVISIBLE (-5275 1100);
FORCEPROP 1 LAST PATH I17
J 0
(-5602 1225);
DISPLAY 0.872340 (-5602 1225);
PAINT GREEN (-5602 1225);
DISPLAY INVISIBLE (-5602 1225);
FORCEADD TAP..6
R 2
(-2875 4675);
FORCEPROP 3 LASTPIN (-2925 4675) SIG_NAME M_H_DQS_DP<17>
J 0
(-2915 4685);
DISPLAY 0.659574 (-2915 4685);
PAINT MONO (-2915 4685);
DISPLAY INVISIBLE (-2915 4685);
FORCEPROP 1 LASTPIN (-2925 4675) BN 17
J 2
(-2873 4683);
DISPLAY 0.617021 (-2873 4683);
PAINT GREEN (-2873 4683);
FORCEPROP 2 LAST CDS_LIB mstr_standard
J 2
(-2875 4675);
PAINT MONO (-2875 4675);
DISPLAY INVISIBLE (-2875 4675);
FORCEPROP 1 LAST BODY_TYPE PLUMBING
J 2
(-2875 4625);
DISPLAY 1.595745 (-2875 4625);
PAINT GREEN (-2875 4625);
DISPLAY INVISIBLE (-2875 4625);
FORCEPROP 1 LAST HDL_TAP TRUE
J 2
(-3200 4550);
DISPLAY 1.595745 (-3200 4550);
PAINT GREEN (-3200 4550);
DISPLAY INVISIBLE (-3200 4550);
FORCEPROP 1 LAST PATH I170
J 2
(-2873 4675);
DISPLAY 0.872340 (-2873 4675);
PAINT GREEN (-2873 4675);
DISPLAY INVISIBLE (-2873 4675);
FORCEADD OFFPAGE..3
(-2025 4750);
FORCEPROP 2 LAST $XR0 79 
J 0
(-1811 4750);
DISPLAY 0.638298 (-1811 4750);
PAINT MONO (-1811 4750);
FORCEPROP 2 LAST $XR1 80 
J 0
(-1721 4750);
DISPLAY 0.638298 (-1721 4750);
PAINT MONO (-1721 4750);
FORCEPROP 2 LAST CDS_LIB mstr_standard
J 0
(-2025 4750);
PAINT MONO (-2025 4750);
DISPLAY INVISIBLE (-2025 4750);
FORCEPROP 1 LAST OFFPAGE TRUE
J 0
(-1700 4625);
DISPLAY 1.170213 (-1700 4625);
PAINT GREEN (-1700 4625);
DISPLAY INVISIBLE (-1700 4625);
FORCEPROP 1 LAST COMMENT_BODY TRUE
J 0
(-2075 4650);
DISPLAY 1.170213 (-2075 4650);
PAINT GREEN (-2075 4650);
DISPLAY INVISIBLE (-2075 4650);
FORCEPROP 2 LAST PATH I171
J 0
(-1825 4825);
DISPLAY 1.021277 (-1825 4825);
PAINT ORANGE (-1825 4825);
DISPLAY INVISIBLE (-1825 4825);
FORCEADD SKX_EXT_B..4
(-4200 2575);
FORCEPROP 1 LAST LOCATION U2D1
J 0
(-5000 4925);
DISPLAY 0.617021 (-5000 4925);
PAINT AQUA (-5000 4925);
FORCEPROP 1 LAST PART_NUMBER TBD
J 0
(-5000 325);
DISPLAY 0.617021 (-5000 325);
PAINT BLUE (-5000 325);
FORCEPROP 1 LAST MATERIAL IC
J 0
(-5000 4875);
DISPLAY 0.617021 (-5000 4875);
PAINT SKYBLUE (-5000 4875);
FORCEPROP 2 LASTPIN (-3350 525) $PN K53
J 0
(-3340 535);
DISPLAY 0.617021 (-3340 535);
PAINT ORANGE (-3340 535);
FORCEPROP 2 LASTPIN (-3350 1575) $PN T47
J 0
(-3340 1585);
DISPLAY 0.617021 (-3340 1585);
PAINT ORANGE (-3340 1585);
FORCEPROP 2 LASTPIN (-3350 1525) $PN M49
J 0
(-3340 1535);
DISPLAY 0.617021 (-3340 1535);
PAINT ORANGE (-3340 1535);
FORCEPROP 2 LASTPIN (-3350 1475) $PN R48
J 0
(-3340 1485);
DISPLAY 0.617021 (-3340 1485);
PAINT ORANGE (-3340 1485);
FORCEPROP 2 LASTPIN (-3350 1425) $PN N50
J 0
(-3340 1435);
DISPLAY 0.617021 (-3340 1435);
PAINT ORANGE (-3340 1435);
FORCEPROP 2 LASTPIN (-3350 2775) $PN N48
J 0
(-3340 2785);
DISPLAY 0.617021 (-3340 2785);
PAINT ORANGE (-3340 2785);
FORCEPROP 2 LASTPIN (-3350 2725) $PN R52
J 0
(-3340 2735);
DISPLAY 0.617021 (-3340 2735);
PAINT ORANGE (-3340 2735);
FORCEPROP 2 LASTPIN (-3350 2675) $PN N52
J 0
(-3340 2685);
DISPLAY 0.617021 (-3340 2685);
PAINT ORANGE (-3340 2685);
FORCEPROP 2 LASTPIN (-3350 2625) $PN T51
J 0
(-3340 2635);
DISPLAY 0.617021 (-3340 2635);
PAINT ORANGE (-3340 2635);
FORCEPROP 2 LASTPIN (-3350 2575) $PN M51
J 0
(-3340 2585);
DISPLAY 0.617021 (-3340 2585);
PAINT ORANGE (-3340 2585);
FORCEPROP 2 LASTPIN (-3350 2525) $PN T61
J 0
(-3340 2535);
DISPLAY 0.617021 (-3340 2535);
PAINT ORANGE (-3340 2535);
FORCEPROP 2 LASTPIN (-3350 2475) $PN R60
J 0
(-3340 2485);
DISPLAY 0.617021 (-3340 2485);
PAINT ORANGE (-3340 2485);
FORCEPROP 2 LASTPIN (-3350 2425) $PN M55
J 0
(-3340 2435);
DISPLAY 0.617021 (-3340 2435);
PAINT ORANGE (-3340 2435);
FORCEPROP 2 LASTPIN (-3350 2375) $PN K59
J 0
(-3340 2385);
DISPLAY 0.617021 (-3340 2385);
PAINT ORANGE (-3340 2385);
FORCEPROP 2 LASTPIN (-3350 2325) $PN W60
J 0
(-3340 2335);
DISPLAY 0.617021 (-3340 2335);
PAINT ORANGE (-3340 2335);
FORCEPROP 2 LASTPIN (-3350 2275) $PN V61
J 0
(-3340 2285);
DISPLAY 0.617021 (-3340 2285);
PAINT ORANGE (-3340 2285);
FORCEPROP 2 LASTPIN (-3350 2225) $PN T59
J 0
(-3340 2235);
DISPLAY 0.617021 (-3340 2235);
PAINT ORANGE (-3340 2235);
FORCEPROP 2 LASTPIN (-3350 2175) $PN R58
J 0
(-3340 2185);
DISPLAY 0.617021 (-3340 2185);
PAINT ORANGE (-3340 2185);
FORCEPROP 2 LASTPIN (-3350 2125) $PN M59
J 0
(-3340 2135);
DISPLAY 0.617021 (-3340 2135);
PAINT ORANGE (-3340 2135);
FORCEPROP 2 LASTPIN (-3350 2075) $PN N58
J 0
(-3340 2085);
DISPLAY 0.617021 (-3340 2085);
PAINT ORANGE (-3340 2085);
FORCEPROP 2 LASTPIN (-3350 2025) $PN K57
J 0
(-3340 2035);
DISPLAY 0.617021 (-3340 2035);
PAINT ORANGE (-3340 2035);
FORCEPROP 2 LASTPIN (-3350 1975) $PN J58
J 0
(-3340 1985);
DISPLAY 0.617021 (-3340 1985);
PAINT ORANGE (-3340 1985);
FORCEPROP 2 LASTPIN (-3350 1925) $PN J52
J 0
(-3340 1935);
DISPLAY 0.617021 (-3340 1935);
PAINT ORANGE (-3340 1935);
FORCEPROP 2 LASTPIN (-5050 1425) $PN M67
J 2
(-5060 1435);
DISPLAY 0.617021 (-5060 1435);
PAINT ORANGE (-5060 1435);
FORCEPROP 2 LASTPIN (-5050 1375) $PN H67
J 2
(-5060 1385);
DISPLAY 0.617021 (-5060 1385);
PAINT ORANGE (-5060 1385);
FORCEPROP 2 LASTPIN (-5050 1325) $PN M69
J 2
(-5060 1335);
DISPLAY 0.617021 (-5060 1335);
PAINT ORANGE (-5060 1335);
FORCEPROP 2 LASTPIN (-5050 1275) $PN L70
J 2
(-5060 1285);
DISPLAY 0.617021 (-5060 1285);
PAINT ORANGE (-5060 1285);
FORCEPROP 2 LASTPIN (-5050 1225) $PN L66
J 2
(-5060 1235);
DISPLAY 0.617021 (-5060 1235);
PAINT ORANGE (-5060 1235);
FORCEPROP 2 LASTPIN (-5050 1175) $PN J66
J 2
(-5060 1185);
DISPLAY 0.617021 (-5060 1185);
PAINT ORANGE (-5060 1185);
FORCEPROP 2 LASTPIN (-5050 1125) $PN H69
J 2
(-5060 1135);
DISPLAY 0.617021 (-5060 1135);
PAINT ORANGE (-5060 1135);
FORCEPROP 2 LASTPIN (-5050 1075) $PN J70
J 2
(-5060 1085);
DISPLAY 0.617021 (-5060 1085);
PAINT ORANGE (-5060 1085);
FORCEPROP 2 LASTPIN (-3350 4675) $PN J68
J 0
(-3340 4685);
DISPLAY 0.617021 (-3340 4685);
PAINT ORANGE (-3340 4685);
FORCEPROP 2 LASTPIN (-3350 4625) $PN V27
J 0
(-3340 4635);
DISPLAY 0.617021 (-3340 4635);
PAINT ORANGE (-3340 4635);
FORCEPROP 2 LASTPIN (-3350 4575) $PN C28
J 0
(-3340 4585);
DISPLAY 0.617021 (-3340 4585);
PAINT ORANGE (-3340 4585);
FORCEPROP 2 LASTPIN (-3350 4525) $PN C34
J 0
(-3340 4535);
DISPLAY 0.617021 (-3340 4535);
PAINT ORANGE (-3340 4535);
FORCEPROP 2 LASTPIN (-3350 4475) $PN L42
J 0
(-3340 4485);
DISPLAY 0.617021 (-3340 4485);
PAINT ORANGE (-3340 4485);
FORCEPROP 2 LASTPIN (-3350 4425) $PN D73
J 0
(-3340 4435);
DISPLAY 0.617021 (-3340 4435);
PAINT ORANGE (-3340 4435);
FORCEPROP 2 LASTPIN (-3350 4375) $PN F79
J 0
(-3340 4385);
DISPLAY 0.617021 (-3340 4385);
PAINT ORANGE (-3340 4385);
FORCEPROP 2 LASTPIN (-3350 4325) $PN AF81
J 0
(-3340 4335);
DISPLAY 0.617021 (-3340 4335);
PAINT ORANGE (-3340 4335);
FORCEPROP 2 LASTPIN (-3350 4275) $PN AT81
J 0
(-3340 4285);
DISPLAY 0.617021 (-3340 4285);
PAINT ORANGE (-3340 4285);
FORCEPROP 2 LASTPIN (-3350 4225) $PN L68
J 0
(-3340 4235);
DISPLAY 0.617021 (-3340 4235);
PAINT ORANGE (-3340 4235);
FORCEPROP 2 LASTPIN (-3350 4175) $PN Y27
J 0
(-3340 4185);
DISPLAY 0.617021 (-3340 4185);
PAINT ORANGE (-3340 4185);
FORCEPROP 2 LASTPIN (-3350 4125) $PN E28
J 0
(-3340 4135);
DISPLAY 0.617021 (-3340 4135);
PAINT ORANGE (-3340 4135);
FORCEPROP 2 LASTPIN (-3350 4075) $PN E34
J 0
(-3340 4085);
DISPLAY 0.617021 (-3340 4085);
PAINT ORANGE (-3340 4085);
FORCEPROP 2 LASTPIN (-3350 4025) $PN R42
J 0
(-3340 4035);
DISPLAY 0.617021 (-3340 4035);
PAINT ORANGE (-3340 4035);
FORCEPROP 2 LASTPIN (-3350 3975) $PN F73
J 0
(-3340 3985);
DISPLAY 0.617021 (-3340 3985);
PAINT ORANGE (-3340 3985);
FORCEPROP 2 LASTPIN (-3350 3925) $PN H79
J 0
(-3340 3935);
DISPLAY 0.617021 (-3340 3935);
PAINT ORANGE (-3340 3935);
FORCEPROP 2 LASTPIN (-3350 3875) $PN AE80
J 0
(-3340 3885);
DISPLAY 0.617021 (-3340 3885);
PAINT ORANGE (-3340 3885);
FORCEPROP 2 LASTPIN (-3350 3825) $PN AR80
J 0
(-3340 3835);
DISPLAY 0.617021 (-3340 3835);
PAINT ORANGE (-3340 3835);
FORCEPROP 2 LASTPIN (-3350 3725) $PN G68
J 0
(-3340 3735);
DISPLAY 0.617021 (-3340 3735);
PAINT ORANGE (-3340 3735);
FORCEPROP 2 LASTPIN (-3350 3675) $PN T27
J 0
(-3340 3685);
DISPLAY 0.617021 (-3340 3685);
PAINT ORANGE (-3340 3685);
FORCEPROP 2 LASTPIN (-3350 3625) $PN A28
J 0
(-3340 3635);
DISPLAY 0.617021 (-3340 3635);
PAINT ORANGE (-3340 3635);
FORCEPROP 2 LASTPIN (-3350 3575) $PN A34
J 0
(-3340 3585);
DISPLAY 0.617021 (-3340 3585);
PAINT ORANGE (-3340 3585);
FORCEPROP 2 LASTPIN (-3350 3525) $PN J42
J 0
(-3340 3535);
DISPLAY 0.617021 (-3340 3535);
PAINT ORANGE (-3340 3535);
FORCEPROP 2 LASTPIN (-3350 3475) $PN B73
J 0
(-3340 3485);
DISPLAY 0.617021 (-3340 3485);
PAINT ORANGE (-3340 3485);
FORCEPROP 2 LASTPIN (-3350 3425) $PN D79
J 0
(-3340 3435);
DISPLAY 0.617021 (-3340 3435);
PAINT ORANGE (-3340 3435);
FORCEPROP 2 LASTPIN (-3350 3375) $PN AG82
J 0
(-3340 3385);
DISPLAY 0.617021 (-3340 3385);
PAINT ORANGE (-3340 3385);
FORCEPROP 2 LASTPIN (-3350 3325) $PN AU82
J 0
(-3340 3335);
DISPLAY 0.617021 (-3340 3335);
PAINT ORANGE (-3340 3335);
FORCEPROP 2 LASTPIN (-3350 3275) $PN N68
J 0
(-3340 3285);
DISPLAY 0.617021 (-3340 3285);
PAINT ORANGE (-3340 3285);
FORCEPROP 2 LASTPIN (-3350 3225) $PN AB27
J 0
(-3340 3235);
DISPLAY 0.617021 (-3340 3235);
PAINT ORANGE (-3340 3235);
FORCEPROP 2 LASTPIN (-3350 3175) $PN G28
J 0
(-3340 3185);
DISPLAY 0.617021 (-3340 3185);
PAINT ORANGE (-3340 3185);
FORCEPROP 2 LASTPIN (-3350 3125) $PN G34
J 0
(-3340 3135);
DISPLAY 0.617021 (-3340 3135);
PAINT ORANGE (-3340 3135);
FORCEPROP 2 LASTPIN (-3350 3075) $PN N42
J 0
(-3340 3085);
DISPLAY 0.617021 (-3340 3085);
PAINT ORANGE (-3340 3085);
FORCEPROP 2 LASTPIN (-3350 3025) $PN H73
J 0
(-3340 3035);
DISPLAY 0.617021 (-3340 3035);
PAINT ORANGE (-3340 3035);
FORCEPROP 2 LASTPIN (-3350 2975) $PN K79
J 0
(-3340 2985);
DISPLAY 0.617021 (-3340 2985);
PAINT ORANGE (-3340 2985);
FORCEPROP 2 LASTPIN (-3350 2925) $PN AD79
J 0
(-3340 2935);
DISPLAY 0.617021 (-3340 2935);
PAINT ORANGE (-3340 2935);
FORCEPROP 2 LASTPIN (-3350 2875) $PN AP79
J 0
(-3340 2885);
DISPLAY 0.617021 (-3340 2885);
PAINT ORANGE (-3340 2885);
FORCEPROP 2 LASTPIN (-5050 4675) $PN AA26
J 2
(-5060 4685);
DISPLAY 0.617021 (-5060 4685);
PAINT ORANGE (-5060 4685);
FORCEPROP 2 LASTPIN (-5050 4625) $PN U26
J 2
(-5060 4635);
DISPLAY 0.617021 (-5060 4635);
PAINT ORANGE (-5060 4635);
FORCEPROP 2 LASTPIN (-5050 4575) $PN Y29
J 2
(-5060 4585);
DISPLAY 0.617021 (-5060 4585);
PAINT ORANGE (-5060 4585);
FORCEPROP 2 LASTPIN (-5050 4525) $PN V29
J 2
(-5060 4535);
DISPLAY 0.617021 (-5060 4535);
PAINT ORANGE (-5060 4535);
FORCEPROP 2 LASTPIN (-5050 4475) $PN Y25
J 2
(-5060 4485);
DISPLAY 0.617021 (-5060 4485);
PAINT ORANGE (-5060 4485);
FORCEPROP 2 LASTPIN (-5050 4425) $PN V25
J 2
(-5060 4435);
DISPLAY 0.617021 (-5060 4435);
PAINT ORANGE (-5060 4435);
FORCEPROP 2 LASTPIN (-5050 4375) $PN AA28
J 2
(-5060 4385);
DISPLAY 0.617021 (-5060 4385);
PAINT ORANGE (-5060 4385);
FORCEPROP 2 LASTPIN (-5050 4325) $PN U28
J 2
(-5060 4335);
DISPLAY 0.617021 (-5060 4335);
PAINT ORANGE (-5060 4335);
FORCEPROP 2 LASTPIN (-5050 4275) $PN F27
J 2
(-5060 4285);
DISPLAY 0.617021 (-5060 4285);
PAINT ORANGE (-5060 4285);
FORCEPROP 2 LASTPIN (-5050 4225) $PN B27
J 2
(-5060 4235);
DISPLAY 0.617021 (-5060 4235);
PAINT ORANGE (-5060 4235);
FORCEPROP 2 LASTPIN (-5050 4175) $PN F29
J 2
(-5060 4185);
DISPLAY 0.617021 (-5060 4185);
PAINT ORANGE (-5060 4185);
FORCEPROP 2 LASTPIN (-5050 4125) $PN E30
J 2
(-5060 4135);
DISPLAY 0.617021 (-5060 4135);
PAINT ORANGE (-5060 4135);
FORCEPROP 2 LASTPIN (-5050 4075) $PN E26
J 2
(-5060 4085);
DISPLAY 0.617021 (-5060 4085);
PAINT ORANGE (-5060 4085);
FORCEPROP 2 LASTPIN (-5050 4025) $PN C26
J 2
(-5060 4035);
DISPLAY 0.617021 (-5060 4035);
PAINT ORANGE (-5060 4035);
FORCEPROP 2 LASTPIN (-5050 3975) $PN B29
J 2
(-5060 3985);
DISPLAY 0.617021 (-5060 3985);
PAINT ORANGE (-5060 3985);
FORCEPROP 2 LASTPIN (-5050 3925) $PN C30
J 2
(-5060 3935);
DISPLAY 0.617021 (-5060 3935);
PAINT ORANGE (-5060 3935);
FORCEPROP 2 LASTPIN (-5050 3875) $PN F33
J 2
(-5060 3885);
DISPLAY 0.617021 (-5060 3885);
PAINT ORANGE (-5060 3885);
FORCEPROP 2 LASTPIN (-5050 3825) $PN B33
J 2
(-5060 3835);
DISPLAY 0.617021 (-5060 3835);
PAINT ORANGE (-5060 3835);
FORCEPROP 2 LASTPIN (-5050 3775) $PN F35
J 2
(-5060 3785);
DISPLAY 0.617021 (-5060 3785);
PAINT ORANGE (-5060 3785);
FORCEPROP 2 LASTPIN (-5050 3725) $PN E36
J 2
(-5060 3735);
DISPLAY 0.617021 (-5060 3735);
PAINT ORANGE (-5060 3735);
FORCEPROP 2 LASTPIN (-5050 3675) $PN E32
J 2
(-5060 3685);
DISPLAY 0.617021 (-5060 3685);
PAINT ORANGE (-5060 3685);
FORCEPROP 2 LASTPIN (-5050 3625) $PN C32
J 2
(-5060 3635);
DISPLAY 0.617021 (-5060 3635);
PAINT ORANGE (-5060 3635);
FORCEPROP 2 LASTPIN (-5050 3575) $PN B35
J 2
(-5060 3585);
DISPLAY 0.617021 (-5060 3585);
PAINT ORANGE (-5060 3585);
FORCEPROP 2 LASTPIN (-5050 3525) $PN C36
J 2
(-5060 3535);
DISPLAY 0.617021 (-5060 3535);
PAINT ORANGE (-5060 3535);
FORCEPROP 2 LASTPIN (-5050 3475) $PN P41
J 2
(-5060 3485);
DISPLAY 0.617021 (-5060 3485);
PAINT ORANGE (-5060 3485);
FORCEPROP 2 LASTPIN (-5050 3425) $PN K41
J 2
(-5060 3435);
DISPLAY 0.617021 (-5060 3435);
PAINT ORANGE (-5060 3435);
FORCEPROP 2 LASTPIN (-5050 3375) $PN T43
J 2
(-5060 3385);
DISPLAY 0.617021 (-5060 3385);
PAINT ORANGE (-5060 3385);
FORCEPROP 2 LASTPIN (-5050 3325) $PN P43
J 2
(-5060 3335);
DISPLAY 0.617021 (-5060 3335);
PAINT ORANGE (-5060 3335);
FORCEPROP 2 LASTPIN (-5050 3275) $PN N40
J 2
(-5060 3285);
DISPLAY 0.617021 (-5060 3285);
PAINT ORANGE (-5060 3285);
FORCEPROP 2 LASTPIN (-5050 3225) $PN L40
J 2
(-5060 3235);
DISPLAY 0.617021 (-5060 3235);
PAINT ORANGE (-5060 3235);
FORCEPROP 2 LASTPIN (-5050 3175) $PN H43
J 2
(-5060 3185);
DISPLAY 0.617021 (-5060 3185);
PAINT ORANGE (-5060 3185);
FORCEPROP 2 LASTPIN (-5050 3125) $PN K43
J 2
(-5060 3135);
DISPLAY 0.617021 (-5060 3135);
PAINT ORANGE (-5060 3135);
FORCEPROP 2 LASTPIN (-5050 3075) $PN G72
J 2
(-5060 3085);
DISPLAY 0.617021 (-5060 3085);
PAINT ORANGE (-5060 3085);
FORCEPROP 2 LASTPIN (-5050 3025) $PN C72
J 2
(-5060 3035);
DISPLAY 0.617021 (-5060 3035);
PAINT ORANGE (-5060 3035);
FORCEPROP 2 LASTPIN (-5050 2975) $PN G74
J 2
(-5060 2985);
DISPLAY 0.617021 (-5060 2985);
PAINT ORANGE (-5060 2985);
FORCEPROP 2 LASTPIN (-5050 2925) $PN F75
J 2
(-5060 2935);
DISPLAY 0.617021 (-5060 2935);
PAINT ORANGE (-5060 2935);
FORCEPROP 2 LASTPIN (-5050 2875) $PN F71
J 2
(-5060 2885);
DISPLAY 0.617021 (-5060 2885);
PAINT ORANGE (-5060 2885);
FORCEPROP 2 LASTPIN (-5050 2825) $PN D71
J 2
(-5060 2835);
DISPLAY 0.617021 (-5060 2835);
PAINT ORANGE (-5060 2835);
FORCEPROP 2 LASTPIN (-5050 2775) $PN C74
J 2
(-5060 2785);
DISPLAY 0.617021 (-5060 2785);
PAINT ORANGE (-5060 2785);
FORCEPROP 2 LASTPIN (-5050 2725) $PN D75
J 2
(-5060 2735);
DISPLAY 0.617021 (-5060 2735);
PAINT ORANGE (-5060 2735);
FORCEPROP 2 LASTPIN (-5050 2675) $PN J78
J 2
(-5060 2685);
DISPLAY 0.617021 (-5060 2685);
PAINT ORANGE (-5060 2685);
FORCEPROP 2 LASTPIN (-5050 2625) $PN E78
J 2
(-5060 2635);
DISPLAY 0.617021 (-5060 2635);
PAINT ORANGE (-5060 2635);
FORCEPROP 2 LASTPIN (-5050 2575) $PN H81
J 2
(-5060 2585);
DISPLAY 0.617021 (-5060 2585);
PAINT ORANGE (-5060 2585);
FORCEPROP 2 LASTPIN (-5050 2525) $PN F81
J 2
(-5060 2535);
DISPLAY 0.617021 (-5060 2535);
PAINT ORANGE (-5060 2535);
FORCEPROP 2 LASTPIN (-5050 2475) $PN H77
J 2
(-5060 2485);
DISPLAY 0.617021 (-5060 2485);
PAINT ORANGE (-5060 2485);
FORCEPROP 2 LASTPIN (-5050 2425) $PN F77
J 2
(-5060 2435);
DISPLAY 0.617021 (-5060 2435);
PAINT ORANGE (-5060 2435);
FORCEPROP 2 LASTPIN (-5050 2375) $PN J80
J 2
(-5060 2385);
DISPLAY 0.617021 (-5060 2385);
PAINT ORANGE (-5060 2385);
FORCEPROP 2 LASTPIN (-5050 2325) $PN E80
J 2
(-5060 2335);
DISPLAY 0.617021 (-5060 2335);
PAINT ORANGE (-5060 2335);
FORCEPROP 2 LASTPIN (-5050 2275) $PN AC80
J 2
(-5060 2285);
DISPLAY 0.617021 (-5060 2285);
PAINT ORANGE (-5060 2285);
FORCEPROP 2 LASTPIN (-5050 2225) $PN AE82
J 2
(-5060 2235);
DISPLAY 0.617021 (-5060 2235);
PAINT ORANGE (-5060 2235);
FORCEPROP 2 LASTPIN (-5050 2175) $PN AH79
J 2
(-5060 2185);
DISPLAY 0.617021 (-5060 2185);
PAINT ORANGE (-5060 2185);
FORCEPROP 2 LASTPIN (-5050 2125) $PN AJ80
J 2
(-5060 2135);
DISPLAY 0.617021 (-5060 2135);
PAINT ORANGE (-5060 2135);
FORCEPROP 2 LASTPIN (-5050 2075) $PN AB81
J 2
(-5060 2085);
DISPLAY 0.617021 (-5060 2085);
PAINT ORANGE (-5060 2085);
FORCEPROP 2 LASTPIN (-5050 2025) $PN AC82
J 2
(-5060 2035);
DISPLAY 0.617021 (-5060 2035);
PAINT ORANGE (-5060 2035);
FORCEPROP 2 LASTPIN (-5050 1975) $PN AF79
J 2
(-5060 1985);
DISPLAY 0.617021 (-5060 1985);
PAINT ORANGE (-5060 1985);
FORCEPROP 2 LASTPIN (-5050 1925) $PN AH81
J 2
(-5060 1935);
DISPLAY 0.617021 (-5060 1935);
PAINT ORANGE (-5060 1935);
FORCEPROP 2 LASTPIN (-5050 1875) $PN AN80
J 2
(-5060 1885);
DISPLAY 0.617021 (-5060 1885);
PAINT ORANGE (-5060 1885);
FORCEPROP 2 LASTPIN (-5050 1825) $PN AR82
J 2
(-5060 1835);
DISPLAY 0.617021 (-5060 1835);
PAINT ORANGE (-5060 1835);
FORCEPROP 2 LASTPIN (-5050 1775) $PN AV79
J 2
(-5060 1785);
DISPLAY 0.617021 (-5060 1785);
PAINT ORANGE (-5060 1785);
FORCEPROP 2 LASTPIN (-5050 1725) $PN AW80
J 2
(-5060 1735);
DISPLAY 0.617021 (-5060 1735);
PAINT ORANGE (-5060 1735);
FORCEPROP 2 LASTPIN (-5050 1675) $PN AM81
J 2
(-5060 1685);
DISPLAY 0.617021 (-5060 1685);
PAINT ORANGE (-5060 1685);
FORCEPROP 2 LASTPIN (-5050 1625) $PN AN82
J 2
(-5060 1635);
DISPLAY 0.617021 (-5060 1635);
PAINT ORANGE (-5060 1635);
FORCEPROP 2 LASTPIN (-5050 1575) $PN AT79
J 2
(-5060 1585);
DISPLAY 0.617021 (-5060 1585);
PAINT ORANGE (-5060 1585);
FORCEPROP 2 LASTPIN (-5050 1525) $PN AV81
J 2
(-5060 1535);
DISPLAY 0.617021 (-5060 1535);
PAINT ORANGE (-5060 1535);
FORCEPROP 2 LASTPIN (-3350 1325) $PN R46
J 0
(-3340 1335);
DISPLAY 0.617021 (-3340 1335);
PAINT ORANGE (-3340 1335);
FORCEPROP 2 LASTPIN (-3350 1275) $PN M45
J 0
(-3340 1285);
DISPLAY 0.617021 (-3340 1285);
PAINT ORANGE (-3340 1285);
FORCEPROP 2 LASTPIN (-3350 1225) $PN T49
J 0
(-3340 1235);
DISPLAY 0.617021 (-3340 1235);
PAINT ORANGE (-3340 1235);
FORCEPROP 2 LASTPIN (-3350 1175) $PN J50
J 0
(-3340 1185);
DISPLAY 0.617021 (-3340 1185);
PAINT ORANGE (-3340 1185);
FORCEPROP 2 LASTPIN (-3350 1125) $PN V47
J 0
(-3340 1135);
DISPLAY 0.617021 (-3340 1135);
PAINT ORANGE (-3340 1135);
FORCEPROP 2 LASTPIN (-3350 1075) $PN N46
J 0
(-3340 1085);
DISPLAY 0.617021 (-3340 1085);
PAINT ORANGE (-3340 1085);
FORCEPROP 2 LASTPIN (-3350 1025) $PN R50
J 0
(-3340 1035);
DISPLAY 0.617021 (-3340 1035);
PAINT ORANGE (-3340 1035);
FORCEPROP 2 LASTPIN (-3350 975) $PN K51
J 0
(-3340 985);
DISPLAY 0.617021 (-3340 985);
PAINT ORANGE (-3340 985);
FORCEPROP 2 LASTPIN (-5050 975) $PN T57
J 2
(-5060 985);
DISPLAY 0.617021 (-5060 985);
PAINT ORANGE (-5060 985);
FORCEPROP 2 LASTPIN (-5050 925) $PN M57
J 2
(-5060 935);
DISPLAY 0.617021 (-5060 935);
PAINT ORANGE (-5060 935);
FORCEPROP 2 LASTPIN (-5050 875) $PN T55
J 2
(-5060 885);
DISPLAY 0.617021 (-5060 885);
PAINT ORANGE (-5060 885);
FORCEPROP 2 LASTPIN (-5050 825) $PN N54
J 2
(-5060 835);
DISPLAY 0.617021 (-5060 835);
PAINT ORANGE (-5060 835);
FORCEPROP 2 LASTPIN (-5050 775) $PN R56
J 2
(-5060 785);
DISPLAY 0.617021 (-5060 785);
PAINT ORANGE (-5060 785);
FORCEPROP 2 LASTPIN (-5050 725) $PN N56
J 2
(-5060 735);
DISPLAY 0.617021 (-5060 735);
PAINT ORANGE (-5060 735);
FORCEPROP 2 LASTPIN (-5050 675) $PN R54
J 2
(-5060 685);
DISPLAY 0.617021 (-5060 685);
PAINT ORANGE (-5060 685);
FORCEPROP 2 LASTPIN (-5050 625) $PN M53
J 2
(-5060 635);
DISPLAY 0.617021 (-5060 635);
PAINT ORANGE (-5060 635);
FORCEPROP 2 LASTPIN (-3350 1825) $PN L64
J 0
(-3340 1835);
DISPLAY 0.617021 (-3340 1835);
PAINT ORANGE (-3340 1835);
FORCEPROP 2 LASTPIN (-3350 1775) $PN K63
J 0
(-3340 1785);
DISPLAY 0.617021 (-3340 1785);
PAINT ORANGE (-3340 1785);
FORCEPROP 2 LASTPIN (-3350 1725) $PN R64
J 0
(-3340 1735);
DISPLAY 0.617021 (-3340 1735);
PAINT ORANGE (-3340 1735);
FORCEPROP 2 LASTPIN (-3350 1675) $PN N62
J 0
(-3340 1685);
DISPLAY 0.617021 (-3340 1685);
PAINT ORANGE (-3340 1685);
FORCEPROP 2 LASTPIN (-5050 525) $PN M47
J 2
(-5060 535);
DISPLAY 0.617021 (-5060 535);
PAINT ORANGE (-5060 535);
FORCEPROP 2 LASTPIN (-3350 875) $PN N60
J 0
(-3340 885);
DISPLAY 0.617021 (-3340 885);
PAINT ORANGE (-3340 885);
FORCEPROP 2 LASTPIN (-3350 825) $PN M61
J 0
(-3340 835);
DISPLAY 0.617021 (-3340 835);
PAINT ORANGE (-3340 835);
FORCEPROP 2 LASTPIN (-3350 775) $PN K55
J 0
(-3340 785);
DISPLAY 0.617021 (-3340 785);
PAINT ORANGE (-3340 785);
FORCEPROP 2 LASTPIN (-3350 725) $PN T53
J 0
(-3340 735);
DISPLAY 0.617021 (-3340 735);
PAINT ORANGE (-3340 735);
FORCEPROP 2 LASTPIN (-3350 575) $PN W62
J 0
(-3340 585);
DISPLAY 0.617021 (-3340 585);
PAINT ORANGE (-3340 585);
FORCEPROP 2 LASTPIN (-3350 625) $PN T63
J 0
(-3340 635);
DISPLAY 0.617021 (-3340 635);
PAINT ORANGE (-3340 635);
FORCEPROP 1 LAST PACK_TYPE BGA1
J 0
(-5000 4975);
PAINT SKYBLUE (-5000 4975);
DISPLAY INVISIBLE (-5000 4975);
FORCEPROP 2 LAST SEC_TYPE BGA1
J 0
(-5000 4975);
DISPLAY 1.021277 (-5000 4975);
PAINT ORANGE (-5000 4975);
DISPLAY INVISIBLE (-5000 4975);
FORCEPROP 2 LAST CDS_LIB chpset_lib
J 0
(-4200 2575);
PAINT ORANGE (-4200 2575);
DISPLAY INVISIBLE (-4200 2575);
FORCEPROP 2 LAST SEC 4
J 0
(-5000 4975);
DISPLAY 0.680851 (-5000 4975);
PAINT MONO (-5000 4975);
DISPLAY INVISIBLE (-5000 4975);
FORCEPROP 2 LAST CDS_LOCATION U2D1
J 0
(-5000 4925);
DISPLAY 0.617021 (-5000 4925);
PAINT AQUA (-5000 4925);
DISPLAY INVISIBLE (-5000 4925);
FORCEPROP 1 LAST PATH I172
J 0
(-4200 4875);
PAINT GREEN (-4200 4875);
DISPLAY INVISIBLE (-4200 4875);
FORCEADD TAP..6
(-5600 1325);
FORCEPROP 3 LASTPIN (-5550 1325) SIG_NAME M_H_ECC<5>
J 0
(-5540 1335);
DISPLAY 0.659574 (-5540 1335);
PAINT MONO (-5540 1335);
DISPLAY INVISIBLE (-5540 1335);
FORCEPROP 1 LASTPIN (-5550 1325) BN 5
J 0
(-5602 1333);
DISPLAY 0.617021 (-5602 1333);
PAINT GREEN (-5602 1333);
FORCEPROP 2 LAST CDS_LIB mstr_standard
J 0
(-5600 1325);
PAINT MONO (-5600 1325);
DISPLAY INVISIBLE (-5600 1325);
FORCEPROP 1 LAST BODY_TYPE PLUMBING
J 0
(-5600 1275);
DISPLAY 1.595745 (-5600 1275);
PAINT GREEN (-5600 1275);
DISPLAY INVISIBLE (-5600 1275);
FORCEPROP 1 LAST HDL_TAP TRUE
J 0
(-5275 1200);
DISPLAY 1.595745 (-5275 1200);
PAINT GREEN (-5275 1200);
DISPLAY INVISIBLE (-5275 1200);
FORCEPROP 1 LAST PATH I18
J 0
(-5602 1325);
DISPLAY 0.872340 (-5602 1325);
PAINT GREEN (-5602 1325);
DISPLAY INVISIBLE (-5602 1325);
FORCEADD TAP..6
(-5600 1375);
FORCEPROP 3 LASTPIN (-5550 1375) SIG_NAME M_H_ECC<6>
J 0
(-5540 1385);
DISPLAY 0.659574 (-5540 1385);
PAINT MONO (-5540 1385);
DISPLAY INVISIBLE (-5540 1385);
FORCEPROP 1 LASTPIN (-5550 1375) BN 6
J 0
(-5602 1383);
DISPLAY 0.617021 (-5602 1383);
PAINT GREEN (-5602 1383);
FORCEPROP 2 LAST CDS_LIB mstr_standard
J 0
(-5600 1375);
PAINT MONO (-5600 1375);
DISPLAY INVISIBLE (-5600 1375);
FORCEPROP 1 LAST BODY_TYPE PLUMBING
J 0
(-5600 1325);
DISPLAY 1.595745 (-5600 1325);
PAINT GREEN (-5600 1325);
DISPLAY INVISIBLE (-5600 1325);
FORCEPROP 1 LAST HDL_TAP TRUE
J 0
(-5275 1250);
DISPLAY 1.595745 (-5275 1250);
PAINT GREEN (-5275 1250);
DISPLAY INVISIBLE (-5275 1250);
FORCEPROP 1 LAST PATH I19
J 0
(-5602 1375);
DISPLAY 0.872340 (-5602 1375);
PAINT GREEN (-5602 1375);
DISPLAY INVISIBLE (-5602 1375);
FORCEADD OFFPAGE..5
(-6450 825);
FORCEPROP 2 LAST $XR0 79 
J 0
(-6674 825);
DISPLAY 0.638298 (-6674 825);
PAINT MONO (-6674 825);
FORCEPROP 2 LAST $XR1 80 
J 0
(-6764 825);
DISPLAY 0.638298 (-6764 825);
PAINT MONO (-6764 825);
FORCEPROP 2 LAST CDS_LIB mstr_standard
J 0
(-6450 825);
PAINT MONO (-6450 825);
DISPLAY INVISIBLE (-6450 825);
FORCEPROP 1 LAST OFFPAGE TRUE
J 0
(-6125 700);
DISPLAY 1.170213 (-6125 700);
PAINT GREEN (-6125 700);
DISPLAY INVISIBLE (-6125 700);
FORCEPROP 1 LAST COMMENT_BODY TRUE
J 0
(-6350 750);
DISPLAY 1.170213 (-6350 750);
PAINT GREEN (-6350 750);
DISPLAY INVISIBLE (-6350 750);
FORCEPROP 2 LAST PATH I2
J 0
(-6400 900);
DISPLAY 1.021277 (-6400 900);
PAINT ORANGE (-6400 900);
DISPLAY INVISIBLE (-6400 900);
FORCEADD TAP..6
(-5600 1425);
FORCEPROP 3 LASTPIN (-5550 1425) SIG_NAME M_H_ECC<7>
J 0
(-5540 1435);
DISPLAY 0.659574 (-5540 1435);
PAINT MONO (-5540 1435);
DISPLAY INVISIBLE (-5540 1435);
FORCEPROP 1 LASTPIN (-5550 1425) BN 7
J 0
(-5602 1433);
DISPLAY 0.617021 (-5602 1433);
PAINT GREEN (-5602 1433);
FORCEPROP 2 LAST CDS_LIB mstr_standard
J 0
(-5600 1425);
PAINT MONO (-5600 1425);
DISPLAY INVISIBLE (-5600 1425);
FORCEPROP 1 LAST BODY_TYPE PLUMBING
J 0
(-5600 1375);
DISPLAY 1.595745 (-5600 1375);
PAINT GREEN (-5600 1375);
DISPLAY INVISIBLE (-5600 1375);
FORCEPROP 1 LAST HDL_TAP TRUE
J 0
(-5275 1300);
DISPLAY 1.595745 (-5275 1300);
PAINT GREEN (-5275 1300);
DISPLAY INVISIBLE (-5275 1300);
FORCEPROP 1 LAST PATH I20
J 0
(-5602 1425);
DISPLAY 0.872340 (-5602 1425);
PAINT GREEN (-5602 1425);
DISPLAY INVISIBLE (-5602 1425);
FORCEADD TAP..6
(-5600 1525);
FORCEPROP 3 LASTPIN (-5550 1525) SIG_NAME M_H_DQ<0>
J 0
(-5540 1535);
DISPLAY 0.659574 (-5540 1535);
PAINT MONO (-5540 1535);
DISPLAY INVISIBLE (-5540 1535);
FORCEPROP 1 LASTPIN (-5550 1525) BN 0
J 0
(-5602 1533);
DISPLAY 0.617021 (-5602 1533);
PAINT GREEN (-5602 1533);
FORCEPROP 2 LAST CDS_LIB mstr_standard
J 0
(-5600 1525);
PAINT MONO (-5600 1525);
DISPLAY INVISIBLE (-5600 1525);
FORCEPROP 1 LAST BODY_TYPE PLUMBING
J 0
(-5600 1475);
DISPLAY 1.595745 (-5600 1475);
PAINT GREEN (-5600 1475);
DISPLAY INVISIBLE (-5600 1475);
FORCEPROP 1 LAST HDL_TAP TRUE
J 0
(-5275 1400);
DISPLAY 1.595745 (-5275 1400);
PAINT GREEN (-5275 1400);
DISPLAY INVISIBLE (-5275 1400);
FORCEPROP 1 LAST PATH I21
J 0
(-5602 1525);
DISPLAY 0.872340 (-5602 1525);
PAINT GREEN (-5602 1525);
DISPLAY INVISIBLE (-5602 1525);
FORCEADD TAP..6
(-5600 1575);
FORCEPROP 3 LASTPIN (-5550 1575) SIG_NAME M_H_DQ<1>
J 0
(-5540 1585);
DISPLAY 0.659574 (-5540 1585);
PAINT MONO (-5540 1585);
DISPLAY INVISIBLE (-5540 1585);
FORCEPROP 1 LASTPIN (-5550 1575) BN 1
J 0
(-5602 1583);
DISPLAY 0.617021 (-5602 1583);
PAINT GREEN (-5602 1583);
FORCEPROP 2 LAST CDS_LIB mstr_standard
J 0
(-5600 1575);
PAINT MONO (-5600 1575);
DISPLAY INVISIBLE (-5600 1575);
FORCEPROP 1 LAST BODY_TYPE PLUMBING
J 0
(-5600 1525);
DISPLAY 1.595745 (-5600 1525);
PAINT GREEN (-5600 1525);
DISPLAY INVISIBLE (-5600 1525);
FORCEPROP 1 LAST HDL_TAP TRUE
J 0
(-5275 1450);
DISPLAY 1.595745 (-5275 1450);
PAINT GREEN (-5275 1450);
DISPLAY INVISIBLE (-5275 1450);
FORCEPROP 1 LAST PATH I22
J 0
(-5602 1575);
DISPLAY 0.872340 (-5602 1575);
PAINT GREEN (-5602 1575);
DISPLAY INVISIBLE (-5602 1575);
FORCEADD TAP..6
(-5600 1625);
FORCEPROP 3 LASTPIN (-5550 1625) SIG_NAME M_H_DQ<2>
J 0
(-5540 1635);
DISPLAY 0.659574 (-5540 1635);
PAINT MONO (-5540 1635);
DISPLAY INVISIBLE (-5540 1635);
FORCEPROP 1 LASTPIN (-5550 1625) BN 2
J 0
(-5602 1633);
DISPLAY 0.617021 (-5602 1633);
PAINT GREEN (-5602 1633);
FORCEPROP 2 LAST CDS_LIB mstr_standard
J 0
(-5600 1625);
PAINT MONO (-5600 1625);
DISPLAY INVISIBLE (-5600 1625);
FORCEPROP 1 LAST BODY_TYPE PLUMBING
J 0
(-5600 1575);
DISPLAY 1.595745 (-5600 1575);
PAINT GREEN (-5600 1575);
DISPLAY INVISIBLE (-5600 1575);
FORCEPROP 1 LAST HDL_TAP TRUE
J 0
(-5275 1500);
DISPLAY 1.595745 (-5275 1500);
PAINT GREEN (-5275 1500);
DISPLAY INVISIBLE (-5275 1500);
FORCEPROP 1 LAST PATH I23
J 0
(-5602 1625);
DISPLAY 0.872340 (-5602 1625);
PAINT GREEN (-5602 1625);
DISPLAY INVISIBLE (-5602 1625);
FORCEADD TAP..6
(-5600 1675);
FORCEPROP 3 LASTPIN (-5550 1675) SIG_NAME M_H_DQ<3>
J 0
(-5540 1685);
DISPLAY 0.659574 (-5540 1685);
PAINT MONO (-5540 1685);
DISPLAY INVISIBLE (-5540 1685);
FORCEPROP 1 LASTPIN (-5550 1675) BN 3
J 0
(-5602 1683);
DISPLAY 0.617021 (-5602 1683);
PAINT GREEN (-5602 1683);
FORCEPROP 2 LAST CDS_LIB mstr_standard
J 0
(-5600 1675);
PAINT MONO (-5600 1675);
DISPLAY INVISIBLE (-5600 1675);
FORCEPROP 1 LAST BODY_TYPE PLUMBING
J 0
(-5600 1625);
DISPLAY 1.595745 (-5600 1625);
PAINT GREEN (-5600 1625);
DISPLAY INVISIBLE (-5600 1625);
FORCEPROP 1 LAST HDL_TAP TRUE
J 0
(-5275 1550);
DISPLAY 1.595745 (-5275 1550);
PAINT GREEN (-5275 1550);
DISPLAY INVISIBLE (-5275 1550);
FORCEPROP 1 LAST PATH I24
J 0
(-5602 1675);
DISPLAY 0.872340 (-5602 1675);
PAINT GREEN (-5602 1675);
DISPLAY INVISIBLE (-5602 1675);
FORCEADD TAP..6
(-5600 1725);
FORCEPROP 3 LASTPIN (-5550 1725) SIG_NAME M_H_DQ<4>
J 0
(-5540 1735);
DISPLAY 0.659574 (-5540 1735);
PAINT MONO (-5540 1735);
DISPLAY INVISIBLE (-5540 1735);
FORCEPROP 1 LASTPIN (-5550 1725) BN 4
J 0
(-5602 1733);
DISPLAY 0.617021 (-5602 1733);
PAINT GREEN (-5602 1733);
FORCEPROP 2 LAST CDS_LIB mstr_standard
J 0
(-5600 1725);
PAINT MONO (-5600 1725);
DISPLAY INVISIBLE (-5600 1725);
FORCEPROP 1 LAST BODY_TYPE PLUMBING
J 0
(-5600 1675);
DISPLAY 1.595745 (-5600 1675);
PAINT GREEN (-5600 1675);
DISPLAY INVISIBLE (-5600 1675);
FORCEPROP 1 LAST HDL_TAP TRUE
J 0
(-5275 1600);
DISPLAY 1.595745 (-5275 1600);
PAINT GREEN (-5275 1600);
DISPLAY INVISIBLE (-5275 1600);
FORCEPROP 1 LAST PATH I25
J 0
(-5602 1725);
DISPLAY 0.872340 (-5602 1725);
PAINT GREEN (-5602 1725);
DISPLAY INVISIBLE (-5602 1725);
FORCEADD TAP..6
(-5600 1775);
FORCEPROP 3 LASTPIN (-5550 1775) SIG_NAME M_H_DQ<5>
J 0
(-5540 1785);
DISPLAY 0.659574 (-5540 1785);
PAINT MONO (-5540 1785);
DISPLAY INVISIBLE (-5540 1785);
FORCEPROP 1 LASTPIN (-5550 1775) BN 5
J 0
(-5602 1783);
DISPLAY 0.617021 (-5602 1783);
PAINT GREEN (-5602 1783);
FORCEPROP 2 LAST CDS_LIB mstr_standard
J 0
(-5600 1775);
PAINT MONO (-5600 1775);
DISPLAY INVISIBLE (-5600 1775);
FORCEPROP 1 LAST BODY_TYPE PLUMBING
J 0
(-5600 1725);
DISPLAY 1.595745 (-5600 1725);
PAINT GREEN (-5600 1725);
DISPLAY INVISIBLE (-5600 1725);
FORCEPROP 1 LAST HDL_TAP TRUE
J 0
(-5275 1650);
DISPLAY 1.595745 (-5275 1650);
PAINT GREEN (-5275 1650);
DISPLAY INVISIBLE (-5275 1650);
FORCEPROP 1 LAST PATH I26
J 0
(-5602 1775);
DISPLAY 0.872340 (-5602 1775);
PAINT GREEN (-5602 1775);
DISPLAY INVISIBLE (-5602 1775);
FORCEADD TAP..6
(-5600 1825);
FORCEPROP 3 LASTPIN (-5550 1825) SIG_NAME M_H_DQ<6>
J 0
(-5540 1835);
DISPLAY 0.659574 (-5540 1835);
PAINT MONO (-5540 1835);
DISPLAY INVISIBLE (-5540 1835);
FORCEPROP 1 LASTPIN (-5550 1825) BN 6
J 0
(-5602 1833);
DISPLAY 0.617021 (-5602 1833);
PAINT GREEN (-5602 1833);
FORCEPROP 2 LAST CDS_LIB mstr_standard
J 0
(-5600 1825);
PAINT MONO (-5600 1825);
DISPLAY INVISIBLE (-5600 1825);
FORCEPROP 1 LAST BODY_TYPE PLUMBING
J 0
(-5600 1775);
DISPLAY 1.595745 (-5600 1775);
PAINT GREEN (-5600 1775);
DISPLAY INVISIBLE (-5600 1775);
FORCEPROP 1 LAST HDL_TAP TRUE
J 0
(-5275 1700);
DISPLAY 1.595745 (-5275 1700);
PAINT GREEN (-5275 1700);
DISPLAY INVISIBLE (-5275 1700);
FORCEPROP 1 LAST PATH I27
J 0
(-5602 1825);
DISPLAY 0.872340 (-5602 1825);
PAINT GREEN (-5602 1825);
DISPLAY INVISIBLE (-5602 1825);
FORCEADD TAP..6
(-5600 1925);
FORCEPROP 3 LASTPIN (-5550 1925) SIG_NAME M_H_DQ<8>
J 0
(-5540 1935);
DISPLAY 0.659574 (-5540 1935);
PAINT MONO (-5540 1935);
DISPLAY INVISIBLE (-5540 1935);
FORCEPROP 1 LASTPIN (-5550 1925) BN 8
J 0
(-5602 1933);
DISPLAY 0.617021 (-5602 1933);
PAINT GREEN (-5602 1933);
FORCEPROP 2 LAST CDS_LIB mstr_standard
J 0
(-5600 1925);
PAINT MONO (-5600 1925);
DISPLAY INVISIBLE (-5600 1925);
FORCEPROP 1 LAST BODY_TYPE PLUMBING
J 0
(-5600 1875);
DISPLAY 1.595745 (-5600 1875);
PAINT GREEN (-5600 1875);
DISPLAY INVISIBLE (-5600 1875);
FORCEPROP 1 LAST HDL_TAP TRUE
J 0
(-5275 1800);
DISPLAY 1.595745 (-5275 1800);
PAINT GREEN (-5275 1800);
DISPLAY INVISIBLE (-5275 1800);
FORCEPROP 1 LAST PATH I28
J 0
(-5602 1925);
DISPLAY 0.872340 (-5602 1925);
PAINT GREEN (-5602 1925);
DISPLAY INVISIBLE (-5602 1925);
FORCEADD TAP..6
(-5600 1875);
FORCEPROP 3 LASTPIN (-5550 1875) SIG_NAME M_H_DQ<7>
J 0
(-5540 1885);
DISPLAY 0.659574 (-5540 1885);
PAINT MONO (-5540 1885);
DISPLAY INVISIBLE (-5540 1885);
FORCEPROP 1 LASTPIN (-5550 1875) BN 7
J 0
(-5602 1883);
DISPLAY 0.617021 (-5602 1883);
PAINT GREEN (-5602 1883);
FORCEPROP 2 LAST CDS_LIB mstr_standard
J 0
(-5600 1875);
PAINT MONO (-5600 1875);
DISPLAY INVISIBLE (-5600 1875);
FORCEPROP 1 LAST BODY_TYPE PLUMBING
J 0
(-5600 1825);
DISPLAY 1.595745 (-5600 1825);
PAINT GREEN (-5600 1825);
DISPLAY INVISIBLE (-5600 1825);
FORCEPROP 1 LAST HDL_TAP TRUE
J 0
(-5275 1750);
DISPLAY 1.595745 (-5275 1750);
PAINT GREEN (-5275 1750);
DISPLAY INVISIBLE (-5275 1750);
FORCEPROP 1 LAST PATH I29
J 0
(-5602 1875);
DISPLAY 0.872340 (-5602 1875);
PAINT GREEN (-5602 1875);
DISPLAY INVISIBLE (-5602 1875);
FORCEADD OFFPAGE..5
(-6450 1025);
FORCEPROP 2 LAST $XR0 79 
J 0
(-6674 1025);
DISPLAY 0.638298 (-6674 1025);
PAINT MONO (-6674 1025);
FORCEPROP 2 LAST $XR1 80 
J 0
(-6764 1025);
DISPLAY 0.638298 (-6764 1025);
PAINT MONO (-6764 1025);
FORCEPROP 2 LAST CDS_LIB mstr_standard
J 0
(-6450 1025);
PAINT MONO (-6450 1025);
DISPLAY INVISIBLE (-6450 1025);
FORCEPROP 1 LAST OFFPAGE TRUE
J 0
(-6125 900);
DISPLAY 1.170213 (-6125 900);
PAINT GREEN (-6125 900);
DISPLAY INVISIBLE (-6125 900);
FORCEPROP 1 LAST COMMENT_BODY TRUE
J 0
(-6350 950);
DISPLAY 1.170213 (-6350 950);
PAINT GREEN (-6350 950);
DISPLAY INVISIBLE (-6350 950);
FORCEPROP 2 LAST PATH I3
J 0
(-6400 1100);
DISPLAY 1.021277 (-6400 1100);
PAINT ORANGE (-6400 1100);
DISPLAY INVISIBLE (-6400 1100);
FORCEADD TAP..6
(-5600 1975);
FORCEPROP 3 LASTPIN (-5550 1975) SIG_NAME M_H_DQ<9>
J 0
(-5540 1985);
DISPLAY 0.659574 (-5540 1985);
PAINT MONO (-5540 1985);
DISPLAY INVISIBLE (-5540 1985);
FORCEPROP 1 LASTPIN (-5550 1975) BN 9
J 0
(-5602 1983);
DISPLAY 0.617021 (-5602 1983);
PAINT GREEN (-5602 1983);
FORCEPROP 2 LAST CDS_LIB mstr_standard
J 0
(-5600 1975);
PAINT MONO (-5600 1975);
DISPLAY INVISIBLE (-5600 1975);
FORCEPROP 1 LAST BODY_TYPE PLUMBING
J 0
(-5600 1925);
DISPLAY 1.595745 (-5600 1925);
PAINT GREEN (-5600 1925);
DISPLAY INVISIBLE (-5600 1925);
FORCEPROP 1 LAST HDL_TAP TRUE
J 0
(-5275 1850);
DISPLAY 1.595745 (-5275 1850);
PAINT GREEN (-5275 1850);
DISPLAY INVISIBLE (-5275 1850);
FORCEPROP 1 LAST PATH I31
J 0
(-5602 1975);
DISPLAY 0.872340 (-5602 1975);
PAINT GREEN (-5602 1975);
DISPLAY INVISIBLE (-5602 1975);
FORCEADD TAP..6
(-5600 2025);
FORCEPROP 3 LASTPIN (-5550 2025) SIG_NAME M_H_DQ<10>
J 0
(-5540 2035);
DISPLAY 0.659574 (-5540 2035);
PAINT MONO (-5540 2035);
DISPLAY INVISIBLE (-5540 2035);
FORCEPROP 1 LASTPIN (-5550 2025) BN 10
J 0
(-5602 2033);
DISPLAY 0.617021 (-5602 2033);
PAINT GREEN (-5602 2033);
FORCEPROP 2 LAST CDS_LIB mstr_standard
J 0
(-5600 2025);
PAINT MONO (-5600 2025);
DISPLAY INVISIBLE (-5600 2025);
FORCEPROP 1 LAST BODY_TYPE PLUMBING
J 0
(-5600 1975);
DISPLAY 1.595745 (-5600 1975);
PAINT GREEN (-5600 1975);
DISPLAY INVISIBLE (-5600 1975);
FORCEPROP 1 LAST HDL_TAP TRUE
J 0
(-5275 1900);
DISPLAY 1.595745 (-5275 1900);
PAINT GREEN (-5275 1900);
DISPLAY INVISIBLE (-5275 1900);
FORCEPROP 1 LAST PATH I32
J 0
(-5602 2025);
DISPLAY 0.872340 (-5602 2025);
PAINT GREEN (-5602 2025);
DISPLAY INVISIBLE (-5602 2025);
FORCEADD TAP..6
(-5600 2075);
FORCEPROP 3 LASTPIN (-5550 2075) SIG_NAME M_H_DQ<11>
J 0
(-5540 2085);
DISPLAY 0.659574 (-5540 2085);
PAINT MONO (-5540 2085);
DISPLAY INVISIBLE (-5540 2085);
FORCEPROP 1 LASTPIN (-5550 2075) BN 11
J 0
(-5602 2083);
DISPLAY 0.617021 (-5602 2083);
PAINT GREEN (-5602 2083);
FORCEPROP 2 LAST CDS_LIB mstr_standard
J 0
(-5600 2075);
PAINT MONO (-5600 2075);
DISPLAY INVISIBLE (-5600 2075);
FORCEPROP 1 LAST BODY_TYPE PLUMBING
J 0
(-5600 2025);
DISPLAY 1.595745 (-5600 2025);
PAINT GREEN (-5600 2025);
DISPLAY INVISIBLE (-5600 2025);
FORCEPROP 1 LAST HDL_TAP TRUE
J 0
(-5275 1950);
DISPLAY 1.595745 (-5275 1950);
PAINT GREEN (-5275 1950);
DISPLAY INVISIBLE (-5275 1950);
FORCEPROP 1 LAST PATH I33
J 0
(-5602 2075);
DISPLAY 0.872340 (-5602 2075);
PAINT GREEN (-5602 2075);
DISPLAY INVISIBLE (-5602 2075);
FORCEADD TAP..6
(-5600 2125);
FORCEPROP 3 LASTPIN (-5550 2125) SIG_NAME M_H_DQ<12>
J 0
(-5540 2135);
DISPLAY 0.659574 (-5540 2135);
PAINT MONO (-5540 2135);
DISPLAY INVISIBLE (-5540 2135);
FORCEPROP 1 LASTPIN (-5550 2125) BN 12
J 0
(-5602 2133);
DISPLAY 0.617021 (-5602 2133);
PAINT GREEN (-5602 2133);
FORCEPROP 2 LAST CDS_LIB mstr_standard
J 0
(-5600 2125);
PAINT MONO (-5600 2125);
DISPLAY INVISIBLE (-5600 2125);
FORCEPROP 1 LAST BODY_TYPE PLUMBING
J 0
(-5600 2075);
DISPLAY 1.595745 (-5600 2075);
PAINT GREEN (-5600 2075);
DISPLAY INVISIBLE (-5600 2075);
FORCEPROP 1 LAST HDL_TAP TRUE
J 0
(-5275 2000);
DISPLAY 1.595745 (-5275 2000);
PAINT GREEN (-5275 2000);
DISPLAY INVISIBLE (-5275 2000);
FORCEPROP 1 LAST PATH I34
J 0
(-5602 2125);
DISPLAY 0.872340 (-5602 2125);
PAINT GREEN (-5602 2125);
DISPLAY INVISIBLE (-5602 2125);
FORCEADD TAP..6
(-5600 2175);
FORCEPROP 3 LASTPIN (-5550 2175) SIG_NAME M_H_DQ<13>
J 0
(-5540 2185);
DISPLAY 0.659574 (-5540 2185);
PAINT MONO (-5540 2185);
DISPLAY INVISIBLE (-5540 2185);
FORCEPROP 1 LASTPIN (-5550 2175) BN 13
J 0
(-5602 2183);
DISPLAY 0.617021 (-5602 2183);
PAINT GREEN (-5602 2183);
FORCEPROP 2 LAST CDS_LIB mstr_standard
J 0
(-5600 2175);
PAINT MONO (-5600 2175);
DISPLAY INVISIBLE (-5600 2175);
FORCEPROP 1 LAST BODY_TYPE PLUMBING
J 0
(-5600 2125);
DISPLAY 1.595745 (-5600 2125);
PAINT GREEN (-5600 2125);
DISPLAY INVISIBLE (-5600 2125);
FORCEPROP 1 LAST HDL_TAP TRUE
J 0
(-5275 2050);
DISPLAY 1.595745 (-5275 2050);
PAINT GREEN (-5275 2050);
DISPLAY INVISIBLE (-5275 2050);
FORCEPROP 1 LAST PATH I35
J 0
(-5602 2175);
DISPLAY 0.872340 (-5602 2175);
PAINT GREEN (-5602 2175);
DISPLAY INVISIBLE (-5602 2175);
FORCEADD TAP..6
(-5600 2225);
FORCEPROP 3 LASTPIN (-5550 2225) SIG_NAME M_H_DQ<14>
J 0
(-5540 2235);
DISPLAY 0.659574 (-5540 2235);
PAINT MONO (-5540 2235);
DISPLAY INVISIBLE (-5540 2235);
FORCEPROP 1 LASTPIN (-5550 2225) BN 14
J 0
(-5602 2233);
DISPLAY 0.617021 (-5602 2233);
PAINT GREEN (-5602 2233);
FORCEPROP 2 LAST CDS_LIB mstr_standard
J 0
(-5600 2225);
PAINT MONO (-5600 2225);
DISPLAY INVISIBLE (-5600 2225);
FORCEPROP 1 LAST BODY_TYPE PLUMBING
J 0
(-5600 2175);
DISPLAY 1.595745 (-5600 2175);
PAINT GREEN (-5600 2175);
DISPLAY INVISIBLE (-5600 2175);
FORCEPROP 1 LAST HDL_TAP TRUE
J 0
(-5275 2100);
DISPLAY 1.595745 (-5275 2100);
PAINT GREEN (-5275 2100);
DISPLAY INVISIBLE (-5275 2100);
FORCEPROP 1 LAST PATH I36
J 0
(-5602 2225);
DISPLAY 0.872340 (-5602 2225);
PAINT GREEN (-5602 2225);
DISPLAY INVISIBLE (-5602 2225);
FORCEADD TAP..6
(-5600 2275);
FORCEPROP 3 LASTPIN (-5550 2275) SIG_NAME M_H_DQ<15>
J 0
(-5540 2285);
DISPLAY 0.659574 (-5540 2285);
PAINT MONO (-5540 2285);
DISPLAY INVISIBLE (-5540 2285);
FORCEPROP 1 LASTPIN (-5550 2275) BN 15
J 0
(-5602 2283);
DISPLAY 0.617021 (-5602 2283);
PAINT GREEN (-5602 2283);
FORCEPROP 2 LAST CDS_LIB mstr_standard
J 0
(-5600 2275);
PAINT MONO (-5600 2275);
DISPLAY INVISIBLE (-5600 2275);
FORCEPROP 1 LAST BODY_TYPE PLUMBING
J 0
(-5600 2225);
DISPLAY 1.595745 (-5600 2225);
PAINT GREEN (-5600 2225);
DISPLAY INVISIBLE (-5600 2225);
FORCEPROP 1 LAST HDL_TAP TRUE
J 0
(-5275 2150);
DISPLAY 1.595745 (-5275 2150);
PAINT GREEN (-5275 2150);
DISPLAY INVISIBLE (-5275 2150);
FORCEPROP 1 LAST PATH I37
J 0
(-5602 2275);
DISPLAY 0.872340 (-5602 2275);
PAINT GREEN (-5602 2275);
DISPLAY INVISIBLE (-5602 2275);
FORCEADD TAP..6
(-5600 2325);
FORCEPROP 3 LASTPIN (-5550 2325) SIG_NAME M_H_DQ<16>
J 0
(-5540 2335);
DISPLAY 0.659574 (-5540 2335);
PAINT MONO (-5540 2335);
DISPLAY INVISIBLE (-5540 2335);
FORCEPROP 1 LASTPIN (-5550 2325) BN 16
J 0
(-5602 2333);
DISPLAY 0.617021 (-5602 2333);
PAINT GREEN (-5602 2333);
FORCEPROP 2 LAST CDS_LIB mstr_standard
J 0
(-5600 2325);
PAINT MONO (-5600 2325);
DISPLAY INVISIBLE (-5600 2325);
FORCEPROP 1 LAST BODY_TYPE PLUMBING
J 0
(-5600 2275);
DISPLAY 1.595745 (-5600 2275);
PAINT GREEN (-5600 2275);
DISPLAY INVISIBLE (-5600 2275);
FORCEPROP 1 LAST HDL_TAP TRUE
J 0
(-5275 2200);
DISPLAY 1.595745 (-5275 2200);
PAINT GREEN (-5275 2200);
DISPLAY INVISIBLE (-5275 2200);
FORCEPROP 1 LAST PATH I38
J 0
(-5602 2325);
DISPLAY 0.872340 (-5602 2325);
PAINT GREEN (-5602 2325);
DISPLAY INVISIBLE (-5602 2325);
FORCEADD TAP..6
(-5600 2375);
FORCEPROP 3 LASTPIN (-5550 2375) SIG_NAME M_H_DQ<17>
J 0
(-5540 2385);
DISPLAY 0.659574 (-5540 2385);
PAINT MONO (-5540 2385);
DISPLAY INVISIBLE (-5540 2385);
FORCEPROP 1 LASTPIN (-5550 2375) BN 17
J 0
(-5602 2383);
DISPLAY 0.617021 (-5602 2383);
PAINT GREEN (-5602 2383);
FORCEPROP 2 LAST CDS_LIB mstr_standard
J 0
(-5600 2375);
PAINT MONO (-5600 2375);
DISPLAY INVISIBLE (-5600 2375);
FORCEPROP 1 LAST BODY_TYPE PLUMBING
J 0
(-5600 2325);
DISPLAY 1.595745 (-5600 2325);
PAINT GREEN (-5600 2325);
DISPLAY INVISIBLE (-5600 2325);
FORCEPROP 1 LAST HDL_TAP TRUE
J 0
(-5275 2250);
DISPLAY 1.595745 (-5275 2250);
PAINT GREEN (-5275 2250);
DISPLAY INVISIBLE (-5275 2250);
FORCEPROP 1 LAST PATH I39
J 0
(-5602 2375);
DISPLAY 0.872340 (-5602 2375);
PAINT GREEN (-5602 2375);
DISPLAY INVISIBLE (-5602 2375);
FORCEADD OFFPAGE..6
(-6450 1475);
FORCEPROP 2 LAST $XR0 79 
J 0
(-6699 1475);
DISPLAY 0.638298 (-6699 1475);
PAINT MONO (-6699 1475);
FORCEPROP 2 LAST $XR1 80 
J 0
(-6789 1475);
DISPLAY 0.638298 (-6789 1475);
PAINT MONO (-6789 1475);
FORCEPROP 2 LAST CDS_LIB mstr_standard
J 0
(-6450 1475);
PAINT MONO (-6450 1475);
DISPLAY INVISIBLE (-6450 1475);
FORCEPROP 1 LAST OFFPAGE TRUE
J 0
(-6125 1350);
DISPLAY 1.170213 (-6125 1350);
PAINT GREEN (-6125 1350);
DISPLAY INVISIBLE (-6125 1350);
FORCEPROP 1 LAST COMMENT_BODY TRUE
J 0
(-6350 1400);
DISPLAY 1.170213 (-6350 1400);
PAINT GREEN (-6350 1400);
DISPLAY INVISIBLE (-6350 1400);
FORCEPROP 2 LAST PATH I4
J 0
(-6400 1550);
DISPLAY 1.021277 (-6400 1550);
PAINT ORANGE (-6400 1550);
DISPLAY INVISIBLE (-6400 1550);
FORCEADD TAP..6
(-5600 2425);
FORCEPROP 3 LASTPIN (-5550 2425) SIG_NAME M_H_DQ<18>
J 0
(-5540 2435);
DISPLAY 0.659574 (-5540 2435);
PAINT MONO (-5540 2435);
DISPLAY INVISIBLE (-5540 2435);
FORCEPROP 1 LASTPIN (-5550 2425) BN 18
J 0
(-5602 2433);
DISPLAY 0.617021 (-5602 2433);
PAINT GREEN (-5602 2433);
FORCEPROP 2 LAST CDS_LIB mstr_standard
J 0
(-5600 2425);
PAINT MONO (-5600 2425);
DISPLAY INVISIBLE (-5600 2425);
FORCEPROP 1 LAST BODY_TYPE PLUMBING
J 0
(-5600 2375);
DISPLAY 1.595745 (-5600 2375);
PAINT GREEN (-5600 2375);
DISPLAY INVISIBLE (-5600 2375);
FORCEPROP 1 LAST HDL_TAP TRUE
J 0
(-5275 2300);
DISPLAY 1.595745 (-5275 2300);
PAINT GREEN (-5275 2300);
DISPLAY INVISIBLE (-5275 2300);
FORCEPROP 1 LAST PATH I40
J 0
(-5602 2425);
DISPLAY 0.872340 (-5602 2425);
PAINT GREEN (-5602 2425);
DISPLAY INVISIBLE (-5602 2425);
FORCEADD TAP..6
(-5600 2475);
FORCEPROP 3 LASTPIN (-5550 2475) SIG_NAME M_H_DQ<19>
J 0
(-5540 2485);
DISPLAY 0.659574 (-5540 2485);
PAINT MONO (-5540 2485);
DISPLAY INVISIBLE (-5540 2485);
FORCEPROP 1 LASTPIN (-5550 2475) BN 19
J 0
(-5602 2483);
DISPLAY 0.617021 (-5602 2483);
PAINT GREEN (-5602 2483);
FORCEPROP 2 LAST CDS_LIB mstr_standard
J 0
(-5600 2475);
PAINT MONO (-5600 2475);
DISPLAY INVISIBLE (-5600 2475);
FORCEPROP 1 LAST BODY_TYPE PLUMBING
J 0
(-5600 2425);
DISPLAY 1.595745 (-5600 2425);
PAINT GREEN (-5600 2425);
DISPLAY INVISIBLE (-5600 2425);
FORCEPROP 1 LAST HDL_TAP TRUE
J 0
(-5275 2350);
DISPLAY 1.595745 (-5275 2350);
PAINT GREEN (-5275 2350);
DISPLAY INVISIBLE (-5275 2350);
FORCEPROP 1 LAST PATH I41
J 0
(-5602 2475);
DISPLAY 0.872340 (-5602 2475);
PAINT GREEN (-5602 2475);
DISPLAY INVISIBLE (-5602 2475);
FORCEADD TAP..6
(-5600 2525);
FORCEPROP 3 LASTPIN (-5550 2525) SIG_NAME M_H_DQ<20>
J 0
(-5540 2535);
DISPLAY 0.659574 (-5540 2535);
PAINT MONO (-5540 2535);
DISPLAY INVISIBLE (-5540 2535);
FORCEPROP 1 LASTPIN (-5550 2525) BN 20
J 0
(-5602 2533);
DISPLAY 0.617021 (-5602 2533);
PAINT GREEN (-5602 2533);
FORCEPROP 2 LAST CDS_LIB mstr_standard
J 0
(-5600 2525);
PAINT MONO (-5600 2525);
DISPLAY INVISIBLE (-5600 2525);
FORCEPROP 1 LAST BODY_TYPE PLUMBING
J 0
(-5600 2475);
DISPLAY 1.595745 (-5600 2475);
PAINT GREEN (-5600 2475);
DISPLAY INVISIBLE (-5600 2475);
FORCEPROP 1 LAST HDL_TAP TRUE
J 0
(-5275 2400);
DISPLAY 1.595745 (-5275 2400);
PAINT GREEN (-5275 2400);
DISPLAY INVISIBLE (-5275 2400);
FORCEPROP 1 LAST PATH I42
J 0
(-5602 2525);
DISPLAY 0.872340 (-5602 2525);
PAINT GREEN (-5602 2525);
DISPLAY INVISIBLE (-5602 2525);
FORCEADD TAP..6
(-5600 2575);
FORCEPROP 3 LASTPIN (-5550 2575) SIG_NAME M_H_DQ<21>
J 0
(-5540 2585);
DISPLAY 0.659574 (-5540 2585);
PAINT MONO (-5540 2585);
DISPLAY INVISIBLE (-5540 2585);
FORCEPROP 1 LASTPIN (-5550 2575) BN 21
J 0
(-5602 2583);
DISPLAY 0.617021 (-5602 2583);
PAINT GREEN (-5602 2583);
FORCEPROP 2 LAST CDS_LIB mstr_standard
J 0
(-5600 2575);
PAINT MONO (-5600 2575);
DISPLAY INVISIBLE (-5600 2575);
FORCEPROP 1 LAST BODY_TYPE PLUMBING
J 0
(-5600 2525);
DISPLAY 1.595745 (-5600 2525);
PAINT GREEN (-5600 2525);
DISPLAY INVISIBLE (-5600 2525);
FORCEPROP 1 LAST HDL_TAP TRUE
J 0
(-5275 2450);
DISPLAY 1.595745 (-5275 2450);
PAINT GREEN (-5275 2450);
DISPLAY INVISIBLE (-5275 2450);
FORCEPROP 1 LAST PATH I43
J 0
(-5602 2575);
DISPLAY 0.872340 (-5602 2575);
PAINT GREEN (-5602 2575);
DISPLAY INVISIBLE (-5602 2575);
FORCEADD TAP..6
(-5600 2625);
FORCEPROP 3 LASTPIN (-5550 2625) SIG_NAME M_H_DQ<22>
J 0
(-5540 2635);
DISPLAY 0.659574 (-5540 2635);
PAINT MONO (-5540 2635);
DISPLAY INVISIBLE (-5540 2635);
FORCEPROP 1 LASTPIN (-5550 2625) BN 22
J 0
(-5602 2633);
DISPLAY 0.617021 (-5602 2633);
PAINT GREEN (-5602 2633);
FORCEPROP 2 LAST CDS_LIB mstr_standard
J 0
(-5600 2625);
PAINT MONO (-5600 2625);
DISPLAY INVISIBLE (-5600 2625);
FORCEPROP 1 LAST BODY_TYPE PLUMBING
J 0
(-5600 2575);
DISPLAY 1.595745 (-5600 2575);
PAINT GREEN (-5600 2575);
DISPLAY INVISIBLE (-5600 2575);
FORCEPROP 1 LAST HDL_TAP TRUE
J 0
(-5275 2500);
DISPLAY 1.595745 (-5275 2500);
PAINT GREEN (-5275 2500);
DISPLAY INVISIBLE (-5275 2500);
FORCEPROP 1 LAST PATH I44
J 0
(-5602 2625);
DISPLAY 0.872340 (-5602 2625);
PAINT GREEN (-5602 2625);
DISPLAY INVISIBLE (-5602 2625);
FORCEADD TAP..6
(-5600 2675);
FORCEPROP 3 LASTPIN (-5550 2675) SIG_NAME M_H_DQ<23>
J 0
(-5540 2685);
DISPLAY 0.659574 (-5540 2685);
PAINT MONO (-5540 2685);
DISPLAY INVISIBLE (-5540 2685);
FORCEPROP 1 LASTPIN (-5550 2675) BN 23
J 0
(-5602 2683);
DISPLAY 0.617021 (-5602 2683);
PAINT GREEN (-5602 2683);
FORCEPROP 2 LAST CDS_LIB mstr_standard
J 0
(-5600 2675);
PAINT MONO (-5600 2675);
DISPLAY INVISIBLE (-5600 2675);
FORCEPROP 1 LAST BODY_TYPE PLUMBING
J 0
(-5600 2625);
DISPLAY 1.595745 (-5600 2625);
PAINT GREEN (-5600 2625);
DISPLAY INVISIBLE (-5600 2625);
FORCEPROP 1 LAST HDL_TAP TRUE
J 0
(-5275 2550);
DISPLAY 1.595745 (-5275 2550);
PAINT GREEN (-5275 2550);
DISPLAY INVISIBLE (-5275 2550);
FORCEPROP 1 LAST PATH I45
J 0
(-5602 2675);
DISPLAY 0.872340 (-5602 2675);
PAINT GREEN (-5602 2675);
DISPLAY INVISIBLE (-5602 2675);
FORCEADD TAP..6
(-5600 2725);
FORCEPROP 3 LASTPIN (-5550 2725) SIG_NAME M_H_DQ<24>
J 0
(-5540 2735);
DISPLAY 0.659574 (-5540 2735);
PAINT MONO (-5540 2735);
DISPLAY INVISIBLE (-5540 2735);
FORCEPROP 1 LASTPIN (-5550 2725) BN 24
J 0
(-5602 2733);
DISPLAY 0.617021 (-5602 2733);
PAINT GREEN (-5602 2733);
FORCEPROP 2 LAST CDS_LIB mstr_standard
J 0
(-5600 2725);
PAINT MONO (-5600 2725);
DISPLAY INVISIBLE (-5600 2725);
FORCEPROP 1 LAST BODY_TYPE PLUMBING
J 0
(-5600 2675);
DISPLAY 1.595745 (-5600 2675);
PAINT GREEN (-5600 2675);
DISPLAY INVISIBLE (-5600 2675);
FORCEPROP 1 LAST HDL_TAP TRUE
J 0
(-5275 2600);
DISPLAY 1.595745 (-5275 2600);
PAINT GREEN (-5275 2600);
DISPLAY INVISIBLE (-5275 2600);
FORCEPROP 1 LAST PATH I46
J 0
(-5602 2725);
DISPLAY 0.872340 (-5602 2725);
PAINT GREEN (-5602 2725);
DISPLAY INVISIBLE (-5602 2725);
FORCEADD TAP..6
(-5600 2825);
FORCEPROP 3 LASTPIN (-5550 2825) SIG_NAME M_H_DQ<26>
J 0
(-5540 2835);
DISPLAY 0.659574 (-5540 2835);
PAINT MONO (-5540 2835);
DISPLAY INVISIBLE (-5540 2835);
FORCEPROP 1 LASTPIN (-5550 2825) BN 26
J 0
(-5602 2833);
DISPLAY 0.617021 (-5602 2833);
PAINT GREEN (-5602 2833);
FORCEPROP 2 LAST CDS_LIB mstr_standard
J 0
(-5600 2825);
PAINT MONO (-5600 2825);
DISPLAY INVISIBLE (-5600 2825);
FORCEPROP 1 LAST BODY_TYPE PLUMBING
J 0
(-5600 2775);
DISPLAY 1.595745 (-5600 2775);
PAINT GREEN (-5600 2775);
DISPLAY INVISIBLE (-5600 2775);
FORCEPROP 1 LAST HDL_TAP TRUE
J 0
(-5275 2700);
DISPLAY 1.595745 (-5275 2700);
PAINT GREEN (-5275 2700);
DISPLAY INVISIBLE (-5275 2700);
FORCEPROP 1 LAST PATH I47
J 0
(-5602 2825);
DISPLAY 0.872340 (-5602 2825);
PAINT GREEN (-5602 2825);
DISPLAY INVISIBLE (-5602 2825);
FORCEADD TAP..6
(-5600 2775);
FORCEPROP 3 LASTPIN (-5550 2775) SIG_NAME M_H_DQ<25>
J 0
(-5540 2785);
DISPLAY 0.659574 (-5540 2785);
PAINT MONO (-5540 2785);
DISPLAY INVISIBLE (-5540 2785);
FORCEPROP 1 LASTPIN (-5550 2775) BN 25
J 0
(-5602 2783);
DISPLAY 0.617021 (-5602 2783);
PAINT GREEN (-5602 2783);
FORCEPROP 2 LAST CDS_LIB mstr_standard
J 0
(-5600 2775);
PAINT MONO (-5600 2775);
DISPLAY INVISIBLE (-5600 2775);
FORCEPROP 1 LAST BODY_TYPE PLUMBING
J 0
(-5600 2725);
DISPLAY 1.595745 (-5600 2725);
PAINT GREEN (-5600 2725);
DISPLAY INVISIBLE (-5600 2725);
FORCEPROP 1 LAST HDL_TAP TRUE
J 0
(-5275 2650);
DISPLAY 1.595745 (-5275 2650);
PAINT GREEN (-5275 2650);
DISPLAY INVISIBLE (-5275 2650);
FORCEPROP 1 LAST PATH I48
J 0
(-5602 2775);
DISPLAY 0.872340 (-5602 2775);
PAINT GREEN (-5602 2775);
DISPLAY INVISIBLE (-5602 2775);
FORCEADD TAP..6
(-5600 2875);
FORCEPROP 3 LASTPIN (-5550 2875) SIG_NAME M_H_DQ<27>
J 0
(-5540 2885);
DISPLAY 0.659574 (-5540 2885);
PAINT MONO (-5540 2885);
DISPLAY INVISIBLE (-5540 2885);
FORCEPROP 1 LASTPIN (-5550 2875) BN 27
J 0
(-5602 2883);
DISPLAY 0.617021 (-5602 2883);
PAINT GREEN (-5602 2883);
FORCEPROP 2 LAST CDS_LIB mstr_standard
J 0
(-5600 2875);
PAINT MONO (-5600 2875);
DISPLAY INVISIBLE (-5600 2875);
FORCEPROP 1 LAST BODY_TYPE PLUMBING
J 0
(-5600 2825);
DISPLAY 1.595745 (-5600 2825);
PAINT GREEN (-5600 2825);
DISPLAY INVISIBLE (-5600 2825);
FORCEPROP 1 LAST HDL_TAP TRUE
J 0
(-5275 2750);
DISPLAY 1.595745 (-5275 2750);
PAINT GREEN (-5275 2750);
DISPLAY INVISIBLE (-5275 2750);
FORCEPROP 1 LAST PATH I49
J 0
(-5602 2875);
DISPLAY 0.872340 (-5602 2875);
PAINT GREEN (-5602 2875);
DISPLAY INVISIBLE (-5602 2875);
FORCEADD TAP..6
(-5600 625);
FORCEPROP 3 LASTPIN (-5550 625) SIG_NAME M_H_CLK_DN<0>
J 0
(-5540 635);
DISPLAY 0.659574 (-5540 635);
PAINT MONO (-5540 635);
DISPLAY INVISIBLE (-5540 635);
FORCEPROP 1 LASTPIN (-5550 625) BN 0
J 0
(-5602 633);
DISPLAY 0.617021 (-5602 633);
PAINT GREEN (-5602 633);
FORCEPROP 2 LAST CDS_LIB mstr_standard
J 0
(-5600 625);
PAINT MONO (-5600 625);
DISPLAY INVISIBLE (-5600 625);
FORCEPROP 1 LAST BODY_TYPE PLUMBING
J 0
(-5600 575);
DISPLAY 1.595745 (-5600 575);
PAINT GREEN (-5600 575);
DISPLAY INVISIBLE (-5600 575);
FORCEPROP 1 LAST HDL_TAP TRUE
J 0
(-5275 500);
DISPLAY 1.595745 (-5275 500);
PAINT GREEN (-5275 500);
DISPLAY INVISIBLE (-5275 500);
FORCEPROP 1 LAST PATH I5
J 0
(-5602 625);
DISPLAY 0.872340 (-5602 625);
PAINT GREEN (-5602 625);
DISPLAY INVISIBLE (-5602 625);
FORCEADD TAP..6
(-5600 2925);
FORCEPROP 3 LASTPIN (-5550 2925) SIG_NAME M_H_DQ<28>
J 0
(-5540 2935);
DISPLAY 0.659574 (-5540 2935);
PAINT MONO (-5540 2935);
DISPLAY INVISIBLE (-5540 2935);
FORCEPROP 1 LASTPIN (-5550 2925) BN 28
J 0
(-5602 2933);
DISPLAY 0.617021 (-5602 2933);
PAINT GREEN (-5602 2933);
FORCEPROP 2 LAST CDS_LIB mstr_standard
J 0
(-5600 2925);
PAINT MONO (-5600 2925);
DISPLAY INVISIBLE (-5600 2925);
FORCEPROP 1 LAST BODY_TYPE PLUMBING
J 0
(-5600 2875);
DISPLAY 1.595745 (-5600 2875);
PAINT GREEN (-5600 2875);
DISPLAY INVISIBLE (-5600 2875);
FORCEPROP 1 LAST HDL_TAP TRUE
J 0
(-5275 2800);
DISPLAY 1.595745 (-5275 2800);
PAINT GREEN (-5275 2800);
DISPLAY INVISIBLE (-5275 2800);
FORCEPROP 1 LAST PATH I50
J 0
(-5602 2925);
DISPLAY 0.872340 (-5602 2925);
PAINT GREEN (-5602 2925);
DISPLAY INVISIBLE (-5602 2925);
FORCEADD TAP..6
(-5600 2975);
FORCEPROP 3 LASTPIN (-5550 2975) SIG_NAME M_H_DQ<29>
J 0
(-5540 2985);
DISPLAY 0.659574 (-5540 2985);
PAINT MONO (-5540 2985);
DISPLAY INVISIBLE (-5540 2985);
FORCEPROP 1 LASTPIN (-5550 2975) BN 29
J 0
(-5602 2983);
DISPLAY 0.617021 (-5602 2983);
PAINT GREEN (-5602 2983);
FORCEPROP 2 LAST CDS_LIB mstr_standard
J 0
(-5600 2975);
PAINT MONO (-5600 2975);
DISPLAY INVISIBLE (-5600 2975);
FORCEPROP 1 LAST BODY_TYPE PLUMBING
J 0
(-5600 2925);
DISPLAY 1.595745 (-5600 2925);
PAINT GREEN (-5600 2925);
DISPLAY INVISIBLE (-5600 2925);
FORCEPROP 1 LAST HDL_TAP TRUE
J 0
(-5275 2850);
DISPLAY 1.595745 (-5275 2850);
PAINT GREEN (-5275 2850);
DISPLAY INVISIBLE (-5275 2850);
FORCEPROP 1 LAST PATH I51
J 0
(-5602 2975);
DISPLAY 0.872340 (-5602 2975);
PAINT GREEN (-5602 2975);
DISPLAY INVISIBLE (-5602 2975);
FORCEADD TAP..6
(-5600 3075);
FORCEPROP 3 LASTPIN (-5550 3075) SIG_NAME M_H_DQ<31>
J 0
(-5540 3085);
DISPLAY 0.659574 (-5540 3085);
PAINT MONO (-5540 3085);
DISPLAY INVISIBLE (-5540 3085);
FORCEPROP 1 LASTPIN (-5550 3075) BN 31
J 0
(-5602 3083);
DISPLAY 0.617021 (-5602 3083);
PAINT GREEN (-5602 3083);
FORCEPROP 2 LAST CDS_LIB mstr_standard
J 0
(-5600 3075);
PAINT MONO (-5600 3075);
DISPLAY INVISIBLE (-5600 3075);
FORCEPROP 1 LAST BODY_TYPE PLUMBING
J 0
(-5600 3025);
DISPLAY 1.595745 (-5600 3025);
PAINT GREEN (-5600 3025);
DISPLAY INVISIBLE (-5600 3025);
FORCEPROP 1 LAST HDL_TAP TRUE
J 0
(-5275 2950);
DISPLAY 1.595745 (-5275 2950);
PAINT GREEN (-5275 2950);
DISPLAY INVISIBLE (-5275 2950);
FORCEPROP 1 LAST PATH I52
J 0
(-5602 3075);
DISPLAY 0.872340 (-5602 3075);
PAINT GREEN (-5602 3075);
DISPLAY INVISIBLE (-5602 3075);
FORCEADD TAP..6
(-5600 3025);
FORCEPROP 3 LASTPIN (-5550 3025) SIG_NAME M_H_DQ<30>
J 0
(-5540 3035);
DISPLAY 0.659574 (-5540 3035);
PAINT MONO (-5540 3035);
DISPLAY INVISIBLE (-5540 3035);
FORCEPROP 1 LASTPIN (-5550 3025) BN 30
J 0
(-5602 3033);
DISPLAY 0.617021 (-5602 3033);
PAINT GREEN (-5602 3033);
FORCEPROP 2 LAST CDS_LIB mstr_standard
J 0
(-5600 3025);
PAINT MONO (-5600 3025);
DISPLAY INVISIBLE (-5600 3025);
FORCEPROP 1 LAST BODY_TYPE PLUMBING
J 0
(-5600 2975);
DISPLAY 1.595745 (-5600 2975);
PAINT GREEN (-5600 2975);
DISPLAY INVISIBLE (-5600 2975);
FORCEPROP 1 LAST HDL_TAP TRUE
J 0
(-5275 2900);
DISPLAY 1.595745 (-5275 2900);
PAINT GREEN (-5275 2900);
DISPLAY INVISIBLE (-5275 2900);
FORCEPROP 1 LAST PATH I53
J 0
(-5602 3025);
DISPLAY 0.872340 (-5602 3025);
PAINT GREEN (-5602 3025);
DISPLAY INVISIBLE (-5602 3025);
FORCEADD TAP..6
(-5600 3125);
FORCEPROP 3 LASTPIN (-5550 3125) SIG_NAME M_H_DQ<32>
J 0
(-5540 3135);
DISPLAY 0.659574 (-5540 3135);
PAINT MONO (-5540 3135);
DISPLAY INVISIBLE (-5540 3135);
FORCEPROP 1 LASTPIN (-5550 3125) BN 32
J 0
(-5602 3133);
DISPLAY 0.617021 (-5602 3133);
PAINT GREEN (-5602 3133);
FORCEPROP 2 LAST CDS_LIB mstr_standard
J 0
(-5600 3125);
PAINT MONO (-5600 3125);
DISPLAY INVISIBLE (-5600 3125);
FORCEPROP 1 LAST BODY_TYPE PLUMBING
J 0
(-5600 3075);
DISPLAY 1.595745 (-5600 3075);
PAINT GREEN (-5600 3075);
DISPLAY INVISIBLE (-5600 3075);
FORCEPROP 1 LAST HDL_TAP TRUE
J 0
(-5275 3000);
DISPLAY 1.595745 (-5275 3000);
PAINT GREEN (-5275 3000);
DISPLAY INVISIBLE (-5275 3000);
FORCEPROP 1 LAST PATH I54
J 0
(-5602 3125);
DISPLAY 0.872340 (-5602 3125);
PAINT GREEN (-5602 3125);
DISPLAY INVISIBLE (-5602 3125);
FORCEADD TAP..6
(-5600 3175);
FORCEPROP 3 LASTPIN (-5550 3175) SIG_NAME M_H_DQ<33>
J 0
(-5540 3185);
DISPLAY 0.659574 (-5540 3185);
PAINT MONO (-5540 3185);
DISPLAY INVISIBLE (-5540 3185);
FORCEPROP 1 LASTPIN (-5550 3175) BN 33
J 0
(-5602 3183);
DISPLAY 0.617021 (-5602 3183);
PAINT GREEN (-5602 3183);
FORCEPROP 2 LAST CDS_LIB mstr_standard
J 0
(-5600 3175);
PAINT MONO (-5600 3175);
DISPLAY INVISIBLE (-5600 3175);
FORCEPROP 1 LAST BODY_TYPE PLUMBING
J 0
(-5600 3125);
DISPLAY 1.595745 (-5600 3125);
PAINT GREEN (-5600 3125);
DISPLAY INVISIBLE (-5600 3125);
FORCEPROP 1 LAST HDL_TAP TRUE
J 0
(-5275 3050);
DISPLAY 1.595745 (-5275 3050);
PAINT GREEN (-5275 3050);
DISPLAY INVISIBLE (-5275 3050);
FORCEPROP 1 LAST PATH I55
J 0
(-5602 3175);
DISPLAY 0.872340 (-5602 3175);
PAINT GREEN (-5602 3175);
DISPLAY INVISIBLE (-5602 3175);
FORCEADD TAP..6
(-5600 3225);
FORCEPROP 3 LASTPIN (-5550 3225) SIG_NAME M_H_DQ<34>
J 0
(-5540 3235);
DISPLAY 0.659574 (-5540 3235);
PAINT MONO (-5540 3235);
DISPLAY INVISIBLE (-5540 3235);
FORCEPROP 1 LASTPIN (-5550 3225) BN 34
J 0
(-5602 3233);
DISPLAY 0.617021 (-5602 3233);
PAINT GREEN (-5602 3233);
FORCEPROP 2 LAST CDS_LIB mstr_standard
J 0
(-5600 3225);
PAINT MONO (-5600 3225);
DISPLAY INVISIBLE (-5600 3225);
FORCEPROP 1 LAST BODY_TYPE PLUMBING
J 0
(-5600 3175);
DISPLAY 1.595745 (-5600 3175);
PAINT GREEN (-5600 3175);
DISPLAY INVISIBLE (-5600 3175);
FORCEPROP 1 LAST HDL_TAP TRUE
J 0
(-5275 3100);
DISPLAY 1.595745 (-5275 3100);
PAINT GREEN (-5275 3100);
DISPLAY INVISIBLE (-5275 3100);
FORCEPROP 1 LAST PATH I56
J 0
(-5602 3225);
DISPLAY 0.872340 (-5602 3225);
PAINT GREEN (-5602 3225);
DISPLAY INVISIBLE (-5602 3225);
FORCEADD TAP..6
(-5600 3325);
FORCEPROP 3 LASTPIN (-5550 3325) SIG_NAME M_H_DQ<36>
J 0
(-5540 3335);
DISPLAY 0.659574 (-5540 3335);
PAINT MONO (-5540 3335);
DISPLAY INVISIBLE (-5540 3335);
FORCEPROP 1 LASTPIN (-5550 3325) BN 36
J 0
(-5602 3333);
DISPLAY 0.617021 (-5602 3333);
PAINT GREEN (-5602 3333);
FORCEPROP 2 LAST CDS_LIB mstr_standard
J 0
(-5600 3325);
PAINT MONO (-5600 3325);
DISPLAY INVISIBLE (-5600 3325);
FORCEPROP 1 LAST BODY_TYPE PLUMBING
J 0
(-5600 3275);
DISPLAY 1.595745 (-5600 3275);
PAINT GREEN (-5600 3275);
DISPLAY INVISIBLE (-5600 3275);
FORCEPROP 1 LAST HDL_TAP TRUE
J 0
(-5275 3200);
DISPLAY 1.595745 (-5275 3200);
PAINT GREEN (-5275 3200);
DISPLAY INVISIBLE (-5275 3200);
FORCEPROP 1 LAST PATH I57
J 0
(-5602 3325);
DISPLAY 0.872340 (-5602 3325);
PAINT GREEN (-5602 3325);
DISPLAY INVISIBLE (-5602 3325);
FORCEADD TAP..6
(-5600 3275);
FORCEPROP 3 LASTPIN (-5550 3275) SIG_NAME M_H_DQ<35>
J 0
(-5540 3285);
DISPLAY 0.659574 (-5540 3285);
PAINT MONO (-5540 3285);
DISPLAY INVISIBLE (-5540 3285);
FORCEPROP 1 LASTPIN (-5550 3275) BN 35
J 0
(-5602 3283);
DISPLAY 0.617021 (-5602 3283);
PAINT GREEN (-5602 3283);
FORCEPROP 2 LAST CDS_LIB mstr_standard
J 0
(-5600 3275);
PAINT MONO (-5600 3275);
DISPLAY INVISIBLE (-5600 3275);
FORCEPROP 1 LAST BODY_TYPE PLUMBING
J 0
(-5600 3225);
DISPLAY 1.595745 (-5600 3225);
PAINT GREEN (-5600 3225);
DISPLAY INVISIBLE (-5600 3225);
FORCEPROP 1 LAST HDL_TAP TRUE
J 0
(-5275 3150);
DISPLAY 1.595745 (-5275 3150);
PAINT GREEN (-5275 3150);
DISPLAY INVISIBLE (-5275 3150);
FORCEPROP 1 LAST PATH I58
J 0
(-5602 3275);
DISPLAY 0.872340 (-5602 3275);
PAINT GREEN (-5602 3275);
DISPLAY INVISIBLE (-5602 3275);
FORCEADD TAP..6
(-5600 3375);
FORCEPROP 3 LASTPIN (-5550 3375) SIG_NAME M_H_DQ<37>
J 0
(-5540 3385);
DISPLAY 0.659574 (-5540 3385);
PAINT MONO (-5540 3385);
DISPLAY INVISIBLE (-5540 3385);
FORCEPROP 1 LASTPIN (-5550 3375) BN 37
J 0
(-5602 3383);
DISPLAY 0.617021 (-5602 3383);
PAINT GREEN (-5602 3383);
FORCEPROP 2 LAST CDS_LIB mstr_standard
J 0
(-5600 3375);
PAINT MONO (-5600 3375);
DISPLAY INVISIBLE (-5600 3375);
FORCEPROP 1 LAST BODY_TYPE PLUMBING
J 0
(-5600 3325);
DISPLAY 1.595745 (-5600 3325);
PAINT GREEN (-5600 3325);
DISPLAY INVISIBLE (-5600 3325);
FORCEPROP 1 LAST HDL_TAP TRUE
J 0
(-5275 3250);
DISPLAY 1.595745 (-5275 3250);
PAINT GREEN (-5275 3250);
DISPLAY INVISIBLE (-5275 3250);
FORCEPROP 1 LAST PATH I59
J 0
(-5602 3375);
DISPLAY 0.872340 (-5602 3375);
PAINT GREEN (-5602 3375);
DISPLAY INVISIBLE (-5602 3375);
FORCEADD TAP..6
(-5600 675);
FORCEPROP 3 LASTPIN (-5550 675) SIG_NAME M_H_CLK_DN<1>
J 0
(-5540 685);
DISPLAY 0.659574 (-5540 685);
PAINT MONO (-5540 685);
DISPLAY INVISIBLE (-5540 685);
FORCEPROP 1 LASTPIN (-5550 675) BN 1
J 0
(-5602 683);
DISPLAY 0.617021 (-5602 683);
PAINT GREEN (-5602 683);
FORCEPROP 2 LAST CDS_LIB mstr_standard
J 0
(-5600 675);
PAINT MONO (-5600 675);
DISPLAY INVISIBLE (-5600 675);
FORCEPROP 1 LAST BODY_TYPE PLUMBING
J 0
(-5600 625);
DISPLAY 1.595745 (-5600 625);
PAINT GREEN (-5600 625);
DISPLAY INVISIBLE (-5600 625);
FORCEPROP 1 LAST HDL_TAP TRUE
J 0
(-5275 550);
DISPLAY 1.595745 (-5275 550);
PAINT GREEN (-5275 550);
DISPLAY INVISIBLE (-5275 550);
FORCEPROP 1 LAST PATH I6
J 0
(-5602 675);
DISPLAY 0.872340 (-5602 675);
PAINT GREEN (-5602 675);
DISPLAY INVISIBLE (-5602 675);
FORCEADD TAP..6
(-5600 3425);
FORCEPROP 3 LASTPIN (-5550 3425) SIG_NAME M_H_DQ<38>
J 0
(-5540 3435);
DISPLAY 0.659574 (-5540 3435);
PAINT MONO (-5540 3435);
DISPLAY INVISIBLE (-5540 3435);
FORCEPROP 1 LASTPIN (-5550 3425) BN 38
J 0
(-5602 3433);
DISPLAY 0.617021 (-5602 3433);
PAINT GREEN (-5602 3433);
FORCEPROP 2 LAST CDS_LIB mstr_standard
J 0
(-5600 3425);
PAINT MONO (-5600 3425);
DISPLAY INVISIBLE (-5600 3425);
FORCEPROP 1 LAST BODY_TYPE PLUMBING
J 0
(-5600 3375);
DISPLAY 1.595745 (-5600 3375);
PAINT GREEN (-5600 3375);
DISPLAY INVISIBLE (-5600 3375);
FORCEPROP 1 LAST HDL_TAP TRUE
J 0
(-5275 3300);
DISPLAY 1.595745 (-5275 3300);
PAINT GREEN (-5275 3300);
DISPLAY INVISIBLE (-5275 3300);
FORCEPROP 1 LAST PATH I60
J 0
(-5602 3425);
DISPLAY 0.872340 (-5602 3425);
PAINT GREEN (-5602 3425);
DISPLAY INVISIBLE (-5602 3425);
FORCEADD TAP..6
(-5600 3475);
FORCEPROP 3 LASTPIN (-5550 3475) SIG_NAME M_H_DQ<39>
J 0
(-5540 3485);
DISPLAY 0.659574 (-5540 3485);
PAINT MONO (-5540 3485);
DISPLAY INVISIBLE (-5540 3485);
FORCEPROP 1 LASTPIN (-5550 3475) BN 39
J 0
(-5602 3483);
DISPLAY 0.617021 (-5602 3483);
PAINT GREEN (-5602 3483);
FORCEPROP 2 LAST CDS_LIB mstr_standard
J 0
(-5600 3475);
PAINT MONO (-5600 3475);
DISPLAY INVISIBLE (-5600 3475);
FORCEPROP 1 LAST BODY_TYPE PLUMBING
J 0
(-5600 3425);
DISPLAY 1.595745 (-5600 3425);
PAINT GREEN (-5600 3425);
DISPLAY INVISIBLE (-5600 3425);
FORCEPROP 1 LAST HDL_TAP TRUE
J 0
(-5275 3350);
DISPLAY 1.595745 (-5275 3350);
PAINT GREEN (-5275 3350);
DISPLAY INVISIBLE (-5275 3350);
FORCEPROP 1 LAST PATH I61
J 0
(-5602 3475);
DISPLAY 0.872340 (-5602 3475);
PAINT GREEN (-5602 3475);
DISPLAY INVISIBLE (-5602 3475);
FORCEADD TAP..6
(-5600 3525);
FORCEPROP 3 LASTPIN (-5550 3525) SIG_NAME M_H_DQ<40>
J 0
(-5540 3535);
DISPLAY 0.659574 (-5540 3535);
PAINT MONO (-5540 3535);
DISPLAY INVISIBLE (-5540 3535);
FORCEPROP 1 LASTPIN (-5550 3525) BN 40
J 0
(-5602 3533);
DISPLAY 0.617021 (-5602 3533);
PAINT GREEN (-5602 3533);
FORCEPROP 2 LAST CDS_LIB mstr_standard
J 0
(-5600 3525);
PAINT MONO (-5600 3525);
DISPLAY INVISIBLE (-5600 3525);
FORCEPROP 1 LAST BODY_TYPE PLUMBING
J 0
(-5600 3475);
DISPLAY 1.595745 (-5600 3475);
PAINT GREEN (-5600 3475);
DISPLAY INVISIBLE (-5600 3475);
FORCEPROP 1 LAST HDL_TAP TRUE
J 0
(-5275 3400);
DISPLAY 1.595745 (-5275 3400);
PAINT GREEN (-5275 3400);
DISPLAY INVISIBLE (-5275 3400);
FORCEPROP 1 LAST PATH I62
J 0
(-5602 3525);
DISPLAY 0.872340 (-5602 3525);
PAINT GREEN (-5602 3525);
DISPLAY INVISIBLE (-5602 3525);
FORCEADD TAP..6
(-5600 3575);
FORCEPROP 3 LASTPIN (-5550 3575) SIG_NAME M_H_DQ<41>
J 0
(-5540 3585);
DISPLAY 0.659574 (-5540 3585);
PAINT MONO (-5540 3585);
DISPLAY INVISIBLE (-5540 3585);
FORCEPROP 1 LASTPIN (-5550 3575) BN 41
J 0
(-5602 3583);
DISPLAY 0.617021 (-5602 3583);
PAINT GREEN (-5602 3583);
FORCEPROP 2 LAST CDS_LIB mstr_standard
J 0
(-5600 3575);
PAINT MONO (-5600 3575);
DISPLAY INVISIBLE (-5600 3575);
FORCEPROP 1 LAST BODY_TYPE PLUMBING
J 0
(-5600 3525);
DISPLAY 1.595745 (-5600 3525);
PAINT GREEN (-5600 3525);
DISPLAY INVISIBLE (-5600 3525);
FORCEPROP 1 LAST HDL_TAP TRUE
J 0
(-5275 3450);
DISPLAY 1.595745 (-5275 3450);
PAINT GREEN (-5275 3450);
DISPLAY INVISIBLE (-5275 3450);
FORCEPROP 1 LAST PATH I63
J 0
(-5602 3575);
DISPLAY 0.872340 (-5602 3575);
PAINT GREEN (-5602 3575);
DISPLAY INVISIBLE (-5602 3575);
FORCEADD TAP..6
(-5600 3625);
FORCEPROP 3 LASTPIN (-5550 3625) SIG_NAME M_H_DQ<42>
J 0
(-5540 3635);
DISPLAY 0.659574 (-5540 3635);
PAINT MONO (-5540 3635);
DISPLAY INVISIBLE (-5540 3635);
FORCEPROP 1 LASTPIN (-5550 3625) BN 42
J 0
(-5602 3633);
DISPLAY 0.617021 (-5602 3633);
PAINT GREEN (-5602 3633);
FORCEPROP 2 LAST CDS_LIB mstr_standard
J 0
(-5600 3625);
PAINT MONO (-5600 3625);
DISPLAY INVISIBLE (-5600 3625);
FORCEPROP 1 LAST BODY_TYPE PLUMBING
J 0
(-5600 3575);
DISPLAY 1.595745 (-5600 3575);
PAINT GREEN (-5600 3575);
DISPLAY INVISIBLE (-5600 3575);
FORCEPROP 1 LAST HDL_TAP TRUE
J 0
(-5275 3500);
DISPLAY 1.595745 (-5275 3500);
PAINT GREEN (-5275 3500);
DISPLAY INVISIBLE (-5275 3500);
FORCEPROP 1 LAST PATH I64
J 0
(-5602 3625);
DISPLAY 0.872340 (-5602 3625);
PAINT GREEN (-5602 3625);
DISPLAY INVISIBLE (-5602 3625);
FORCEADD TAP..6
(-5600 3675);
FORCEPROP 3 LASTPIN (-5550 3675) SIG_NAME M_H_DQ<43>
J 0
(-5540 3685);
DISPLAY 0.659574 (-5540 3685);
PAINT MONO (-5540 3685);
DISPLAY INVISIBLE (-5540 3685);
FORCEPROP 1 LASTPIN (-5550 3675) BN 43
J 0
(-5602 3683);
DISPLAY 0.617021 (-5602 3683);
PAINT GREEN (-5602 3683);
FORCEPROP 2 LAST CDS_LIB mstr_standard
J 0
(-5600 3675);
PAINT MONO (-5600 3675);
DISPLAY INVISIBLE (-5600 3675);
FORCEPROP 1 LAST BODY_TYPE PLUMBING
J 0
(-5600 3625);
DISPLAY 1.595745 (-5600 3625);
PAINT GREEN (-5600 3625);
DISPLAY INVISIBLE (-5600 3625);
FORCEPROP 1 LAST HDL_TAP TRUE
J 0
(-5275 3550);
DISPLAY 1.595745 (-5275 3550);
PAINT GREEN (-5275 3550);
DISPLAY INVISIBLE (-5275 3550);
FORCEPROP 1 LAST PATH I65
J 0
(-5602 3675);
DISPLAY 0.872340 (-5602 3675);
PAINT GREEN (-5602 3675);
DISPLAY INVISIBLE (-5602 3675);
FORCEADD TAP..6
(-5600 3725);
FORCEPROP 3 LASTPIN (-5550 3725) SIG_NAME M_H_DQ<44>
J 0
(-5540 3735);
DISPLAY 0.659574 (-5540 3735);
PAINT MONO (-5540 3735);
DISPLAY INVISIBLE (-5540 3735);
FORCEPROP 1 LASTPIN (-5550 3725) BN 44
J 0
(-5602 3733);
DISPLAY 0.617021 (-5602 3733);
PAINT GREEN (-5602 3733);
FORCEPROP 2 LAST CDS_LIB mstr_standard
J 0
(-5600 3725);
PAINT MONO (-5600 3725);
DISPLAY INVISIBLE (-5600 3725);
FORCEPROP 1 LAST BODY_TYPE PLUMBING
J 0
(-5600 3675);
DISPLAY 1.595745 (-5600 3675);
PAINT GREEN (-5600 3675);
DISPLAY INVISIBLE (-5600 3675);
FORCEPROP 1 LAST HDL_TAP TRUE
J 0
(-5275 3600);
DISPLAY 1.595745 (-5275 3600);
PAINT GREEN (-5275 3600);
DISPLAY INVISIBLE (-5275 3600);
FORCEPROP 1 LAST PATH I66
J 0
(-5602 3725);
DISPLAY 0.872340 (-5602 3725);
PAINT GREEN (-5602 3725);
DISPLAY INVISIBLE (-5602 3725);
FORCEADD TAP..6
(-5600 3775);
FORCEPROP 3 LASTPIN (-5550 3775) SIG_NAME M_H_DQ<45>
J 0
(-5540 3785);
DISPLAY 0.659574 (-5540 3785);
PAINT MONO (-5540 3785);
DISPLAY INVISIBLE (-5540 3785);
FORCEPROP 1 LASTPIN (-5550 3775) BN 45
J 0
(-5602 3783);
DISPLAY 0.617021 (-5602 3783);
PAINT GREEN (-5602 3783);
FORCEPROP 2 LAST CDS_LIB mstr_standard
J 0
(-5600 3775);
PAINT MONO (-5600 3775);
DISPLAY INVISIBLE (-5600 3775);
FORCEPROP 1 LAST BODY_TYPE PLUMBING
J 0
(-5600 3725);
DISPLAY 1.595745 (-5600 3725);
PAINT GREEN (-5600 3725);
DISPLAY INVISIBLE (-5600 3725);
FORCEPROP 1 LAST HDL_TAP TRUE
J 0
(-5275 3650);
DISPLAY 1.595745 (-5275 3650);
PAINT GREEN (-5275 3650);
DISPLAY INVISIBLE (-5275 3650);
FORCEPROP 1 LAST PATH I67
J 0
(-5602 3775);
DISPLAY 0.872340 (-5602 3775);
PAINT GREEN (-5602 3775);
DISPLAY INVISIBLE (-5602 3775);
FORCEADD TAP..6
(-5600 3825);
FORCEPROP 3 LASTPIN (-5550 3825) SIG_NAME M_H_DQ<46>
J 0
(-5540 3835);
DISPLAY 0.659574 (-5540 3835);
PAINT MONO (-5540 3835);
DISPLAY INVISIBLE (-5540 3835);
FORCEPROP 1 LASTPIN (-5550 3825) BN 46
J 0
(-5602 3833);
DISPLAY 0.617021 (-5602 3833);
PAINT GREEN (-5602 3833);
FORCEPROP 2 LAST CDS_LIB mstr_standard
J 0
(-5600 3825);
PAINT MONO (-5600 3825);
DISPLAY INVISIBLE (-5600 3825);
FORCEPROP 1 LAST BODY_TYPE PLUMBING
J 0
(-5600 3775);
DISPLAY 1.595745 (-5600 3775);
PAINT GREEN (-5600 3775);
DISPLAY INVISIBLE (-5600 3775);
FORCEPROP 1 LAST HDL_TAP TRUE
J 0
(-5275 3700);
DISPLAY 1.595745 (-5275 3700);
PAINT GREEN (-5275 3700);
DISPLAY INVISIBLE (-5275 3700);
FORCEPROP 1 LAST PATH I68
J 0
(-5602 3825);
DISPLAY 0.872340 (-5602 3825);
PAINT GREEN (-5602 3825);
DISPLAY INVISIBLE (-5602 3825);
FORCEADD TAP..6
(-5600 3875);
FORCEPROP 3 LASTPIN (-5550 3875) SIG_NAME M_H_DQ<47>
J 0
(-5540 3885);
DISPLAY 0.659574 (-5540 3885);
PAINT MONO (-5540 3885);
DISPLAY INVISIBLE (-5540 3885);
FORCEPROP 1 LASTPIN (-5550 3875) BN 47
J 0
(-5602 3883);
DISPLAY 0.617021 (-5602 3883);
PAINT GREEN (-5602 3883);
FORCEPROP 2 LAST CDS_LIB mstr_standard
J 0
(-5600 3875);
PAINT MONO (-5600 3875);
DISPLAY INVISIBLE (-5600 3875);
FORCEPROP 1 LAST BODY_TYPE PLUMBING
J 0
(-5600 3825);
DISPLAY 1.595745 (-5600 3825);
PAINT GREEN (-5600 3825);
DISPLAY INVISIBLE (-5600 3825);
FORCEPROP 1 LAST HDL_TAP TRUE
J 0
(-5275 3750);
DISPLAY 1.595745 (-5275 3750);
PAINT GREEN (-5275 3750);
DISPLAY INVISIBLE (-5275 3750);
FORCEPROP 1 LAST PATH I69
J 0
(-5602 3875);
DISPLAY 0.872340 (-5602 3875);
PAINT GREEN (-5602 3875);
DISPLAY INVISIBLE (-5602 3875);
FORCEADD TAP..6
(-5600 775);
FORCEPROP 3 LASTPIN (-5550 775) SIG_NAME M_H_CLK_DN<3>
J 0
(-5540 785);
DISPLAY 0.659574 (-5540 785);
PAINT MONO (-5540 785);
DISPLAY INVISIBLE (-5540 785);
FORCEPROP 1 LASTPIN (-5550 775) BN 3
J 0
(-5602 783);
DISPLAY 0.617021 (-5602 783);
PAINT GREEN (-5602 783);
FORCEPROP 2 LAST CDS_LIB mstr_standard
J 0
(-5600 775);
PAINT MONO (-5600 775);
DISPLAY INVISIBLE (-5600 775);
FORCEPROP 1 LAST BODY_TYPE PLUMBING
J 0
(-5600 725);
DISPLAY 1.595745 (-5600 725);
PAINT GREEN (-5600 725);
DISPLAY INVISIBLE (-5600 725);
FORCEPROP 1 LAST HDL_TAP TRUE
J 0
(-5275 650);
DISPLAY 1.595745 (-5275 650);
PAINT GREEN (-5275 650);
DISPLAY INVISIBLE (-5275 650);
FORCEPROP 1 LAST PATH I7
J 0
(-5602 775);
DISPLAY 0.872340 (-5602 775);
PAINT GREEN (-5602 775);
DISPLAY INVISIBLE (-5602 775);
FORCEADD TAP..6
(-5600 3925);
FORCEPROP 3 LASTPIN (-5550 3925) SIG_NAME M_H_DQ<48>
J 0
(-5540 3935);
DISPLAY 0.659574 (-5540 3935);
PAINT MONO (-5540 3935);
DISPLAY INVISIBLE (-5540 3935);
FORCEPROP 1 LASTPIN (-5550 3925) BN 48
J 0
(-5602 3933);
DISPLAY 0.617021 (-5602 3933);
PAINT GREEN (-5602 3933);
FORCEPROP 2 LAST CDS_LIB mstr_standard
J 0
(-5600 3925);
PAINT MONO (-5600 3925);
DISPLAY INVISIBLE (-5600 3925);
FORCEPROP 1 LAST BODY_TYPE PLUMBING
J 0
(-5600 3875);
DISPLAY 1.595745 (-5600 3875);
PAINT GREEN (-5600 3875);
DISPLAY INVISIBLE (-5600 3875);
FORCEPROP 1 LAST HDL_TAP TRUE
J 0
(-5275 3800);
DISPLAY 1.595745 (-5275 3800);
PAINT GREEN (-5275 3800);
DISPLAY INVISIBLE (-5275 3800);
FORCEPROP 1 LAST PATH I70
J 0
(-5602 3925);
DISPLAY 0.872340 (-5602 3925);
PAINT GREEN (-5602 3925);
DISPLAY INVISIBLE (-5602 3925);
FORCEADD TAP..6
(-5600 3975);
FORCEPROP 3 LASTPIN (-5550 3975) SIG_NAME M_H_DQ<49>
J 0
(-5540 3985);
DISPLAY 0.659574 (-5540 3985);
PAINT MONO (-5540 3985);
DISPLAY INVISIBLE (-5540 3985);
FORCEPROP 1 LASTPIN (-5550 3975) BN 49
J 0
(-5602 3983);
DISPLAY 0.617021 (-5602 3983);
PAINT GREEN (-5602 3983);
FORCEPROP 2 LAST CDS_LIB mstr_standard
J 0
(-5600 3975);
PAINT MONO (-5600 3975);
DISPLAY INVISIBLE (-5600 3975);
FORCEPROP 1 LAST BODY_TYPE PLUMBING
J 0
(-5600 3925);
DISPLAY 1.595745 (-5600 3925);
PAINT GREEN (-5600 3925);
DISPLAY INVISIBLE (-5600 3925);
FORCEPROP 1 LAST HDL_TAP TRUE
J 0
(-5275 3850);
DISPLAY 1.595745 (-5275 3850);
PAINT GREEN (-5275 3850);
DISPLAY INVISIBLE (-5275 3850);
FORCEPROP 1 LAST PATH I71
J 0
(-5602 3975);
DISPLAY 0.872340 (-5602 3975);
PAINT GREEN (-5602 3975);
DISPLAY INVISIBLE (-5602 3975);
FORCEADD OFFPAGE..6
(-6450 4800);
FORCEPROP 2 LAST $XR0 79 
J 0
(-6699 4800);
DISPLAY 0.638298 (-6699 4800);
PAINT MONO (-6699 4800);
FORCEPROP 2 LAST $XR1 80 
J 0
(-6789 4800);
DISPLAY 0.638298 (-6789 4800);
PAINT MONO (-6789 4800);
FORCEPROP 2 LAST CDS_LIB mstr_standard
J 0
(-6450 4800);
PAINT MONO (-6450 4800);
DISPLAY INVISIBLE (-6450 4800);
FORCEPROP 1 LAST OFFPAGE TRUE
J 0
(-6125 4675);
DISPLAY 1.170213 (-6125 4675);
PAINT GREEN (-6125 4675);
DISPLAY INVISIBLE (-6125 4675);
FORCEPROP 1 LAST COMMENT_BODY TRUE
J 0
(-6350 4725);
DISPLAY 1.170213 (-6350 4725);
PAINT GREEN (-6350 4725);
DISPLAY INVISIBLE (-6350 4725);
FORCEPROP 2 LAST PATH I72
J 0
(-6400 4875);
DISPLAY 1.021277 (-6400 4875);
PAINT ORANGE (-6400 4875);
DISPLAY INVISIBLE (-6400 4875);
FORCEADD TAP..6
(-5600 4025);
FORCEPROP 3 LASTPIN (-5550 4025) SIG_NAME M_H_DQ<50>
J 0
(-5540 4035);
DISPLAY 0.659574 (-5540 4035);
PAINT MONO (-5540 4035);
DISPLAY INVISIBLE (-5540 4035);
FORCEPROP 1 LASTPIN (-5550 4025) BN 50
J 0
(-5602 4033);
DISPLAY 0.617021 (-5602 4033);
PAINT GREEN (-5602 4033);
FORCEPROP 2 LAST CDS_LIB mstr_standard
J 0
(-5600 4025);
PAINT MONO (-5600 4025);
DISPLAY INVISIBLE (-5600 4025);
FORCEPROP 1 LAST BODY_TYPE PLUMBING
J 0
(-5600 3975);
DISPLAY 1.595745 (-5600 3975);
PAINT GREEN (-5600 3975);
DISPLAY INVISIBLE (-5600 3975);
FORCEPROP 1 LAST HDL_TAP TRUE
J 0
(-5275 3900);
DISPLAY 1.595745 (-5275 3900);
PAINT GREEN (-5275 3900);
DISPLAY INVISIBLE (-5275 3900);
FORCEPROP 1 LAST PATH I73
J 0
(-5602 4025);
DISPLAY 0.872340 (-5602 4025);
PAINT GREEN (-5602 4025);
DISPLAY INVISIBLE (-5602 4025);
FORCEADD TAP..6
(-5600 4075);
FORCEPROP 3 LASTPIN (-5550 4075) SIG_NAME M_H_DQ<51>
J 0
(-5540 4085);
DISPLAY 0.659574 (-5540 4085);
PAINT MONO (-5540 4085);
DISPLAY INVISIBLE (-5540 4085);
FORCEPROP 1 LASTPIN (-5550 4075) BN 51
J 0
(-5602 4083);
DISPLAY 0.617021 (-5602 4083);
PAINT GREEN (-5602 4083);
FORCEPROP 2 LAST CDS_LIB mstr_standard
J 0
(-5600 4075);
PAINT MONO (-5600 4075);
DISPLAY INVISIBLE (-5600 4075);
FORCEPROP 1 LAST BODY_TYPE PLUMBING
J 0
(-5600 4025);
DISPLAY 1.595745 (-5600 4025);
PAINT GREEN (-5600 4025);
DISPLAY INVISIBLE (-5600 4025);
FORCEPROP 1 LAST HDL_TAP TRUE
J 0
(-5275 3950);
DISPLAY 1.595745 (-5275 3950);
PAINT GREEN (-5275 3950);
DISPLAY INVISIBLE (-5275 3950);
FORCEPROP 1 LAST PATH I74
J 0
(-5602 4075);
DISPLAY 0.872340 (-5602 4075);
PAINT GREEN (-5602 4075);
DISPLAY INVISIBLE (-5602 4075);
FORCEADD TAP..6
(-5600 4125);
FORCEPROP 3 LASTPIN (-5550 4125) SIG_NAME M_H_DQ<52>
J 0
(-5540 4135);
DISPLAY 0.659574 (-5540 4135);
PAINT MONO (-5540 4135);
DISPLAY INVISIBLE (-5540 4135);
FORCEPROP 1 LASTPIN (-5550 4125) BN 52
J 0
(-5602 4133);
DISPLAY 0.617021 (-5602 4133);
PAINT GREEN (-5602 4133);
FORCEPROP 2 LAST CDS_LIB mstr_standard
J 0
(-5600 4125);
PAINT MONO (-5600 4125);
DISPLAY INVISIBLE (-5600 4125);
FORCEPROP 1 LAST BODY_TYPE PLUMBING
J 0
(-5600 4075);
DISPLAY 1.595745 (-5600 4075);
PAINT GREEN (-5600 4075);
DISPLAY INVISIBLE (-5600 4075);
FORCEPROP 1 LAST HDL_TAP TRUE
J 0
(-5275 4000);
DISPLAY 1.595745 (-5275 4000);
PAINT GREEN (-5275 4000);
DISPLAY INVISIBLE (-5275 4000);
FORCEPROP 1 LAST PATH I75
J 0
(-5602 4125);
DISPLAY 0.872340 (-5602 4125);
PAINT GREEN (-5602 4125);
DISPLAY INVISIBLE (-5602 4125);
FORCEADD TAP..6
(-5600 4175);
FORCEPROP 3 LASTPIN (-5550 4175) SIG_NAME M_H_DQ<53>
J 0
(-5540 4185);
DISPLAY 0.659574 (-5540 4185);
PAINT MONO (-5540 4185);
DISPLAY INVISIBLE (-5540 4185);
FORCEPROP 1 LASTPIN (-5550 4175) BN 53
J 0
(-5602 4183);
DISPLAY 0.617021 (-5602 4183);
PAINT GREEN (-5602 4183);
FORCEPROP 2 LAST CDS_LIB mstr_standard
J 0
(-5600 4175);
PAINT MONO (-5600 4175);
DISPLAY INVISIBLE (-5600 4175);
FORCEPROP 1 LAST BODY_TYPE PLUMBING
J 0
(-5600 4125);
DISPLAY 1.595745 (-5600 4125);
PAINT GREEN (-5600 4125);
DISPLAY INVISIBLE (-5600 4125);
FORCEPROP 1 LAST HDL_TAP TRUE
J 0
(-5275 4050);
DISPLAY 1.595745 (-5275 4050);
PAINT GREEN (-5275 4050);
DISPLAY INVISIBLE (-5275 4050);
FORCEPROP 1 LAST PATH I76
J 0
(-5602 4175);
DISPLAY 0.872340 (-5602 4175);
PAINT GREEN (-5602 4175);
DISPLAY INVISIBLE (-5602 4175);
FORCEADD TAP..6
(-5600 4225);
FORCEPROP 3 LASTPIN (-5550 4225) SIG_NAME M_H_DQ<54>
J 0
(-5540 4235);
DISPLAY 0.659574 (-5540 4235);
PAINT MONO (-5540 4235);
DISPLAY INVISIBLE (-5540 4235);
FORCEPROP 1 LASTPIN (-5550 4225) BN 54
J 0
(-5602 4233);
DISPLAY 0.617021 (-5602 4233);
PAINT GREEN (-5602 4233);
FORCEPROP 2 LAST CDS_LIB mstr_standard
J 0
(-5600 4225);
PAINT MONO (-5600 4225);
DISPLAY INVISIBLE (-5600 4225);
FORCEPROP 1 LAST BODY_TYPE PLUMBING
J 0
(-5600 4175);
DISPLAY 1.595745 (-5600 4175);
PAINT GREEN (-5600 4175);
DISPLAY INVISIBLE (-5600 4175);
FORCEPROP 1 LAST HDL_TAP TRUE
J 0
(-5275 4100);
DISPLAY 1.595745 (-5275 4100);
PAINT GREEN (-5275 4100);
DISPLAY INVISIBLE (-5275 4100);
FORCEPROP 1 LAST PATH I77
J 0
(-5602 4225);
DISPLAY 0.872340 (-5602 4225);
PAINT GREEN (-5602 4225);
DISPLAY INVISIBLE (-5602 4225);
FORCEADD TAP..6
(-5600 4275);
FORCEPROP 3 LASTPIN (-5550 4275) SIG_NAME M_H_DQ<55>
J 0
(-5540 4285);
DISPLAY 0.659574 (-5540 4285);
PAINT MONO (-5540 4285);
DISPLAY INVISIBLE (-5540 4285);
FORCEPROP 1 LASTPIN (-5550 4275) BN 55
J 0
(-5602 4283);
DISPLAY 0.617021 (-5602 4283);
PAINT GREEN (-5602 4283);
FORCEPROP 2 LAST CDS_LIB mstr_standard
J 0
(-5600 4275);
PAINT MONO (-5600 4275);
DISPLAY INVISIBLE (-5600 4275);
FORCEPROP 1 LAST BODY_TYPE PLUMBING
J 0
(-5600 4225);
DISPLAY 1.595745 (-5600 4225);
PAINT GREEN (-5600 4225);
DISPLAY INVISIBLE (-5600 4225);
FORCEPROP 1 LAST HDL_TAP TRUE
J 0
(-5275 4150);
DISPLAY 1.595745 (-5275 4150);
PAINT GREEN (-5275 4150);
DISPLAY INVISIBLE (-5275 4150);
FORCEPROP 1 LAST PATH I78
J 0
(-5602 4275);
DISPLAY 0.872340 (-5602 4275);
PAINT GREEN (-5602 4275);
DISPLAY INVISIBLE (-5602 4275);
FORCEADD TAP..6
(-5600 4325);
FORCEPROP 3 LASTPIN (-5550 4325) SIG_NAME M_H_DQ<56>
J 0
(-5540 4335);
DISPLAY 0.659574 (-5540 4335);
PAINT MONO (-5540 4335);
DISPLAY INVISIBLE (-5540 4335);
FORCEPROP 1 LASTPIN (-5550 4325) BN 56
J 0
(-5602 4333);
DISPLAY 0.617021 (-5602 4333);
PAINT GREEN (-5602 4333);
FORCEPROP 2 LAST CDS_LIB mstr_standard
J 0
(-5600 4325);
PAINT MONO (-5600 4325);
DISPLAY INVISIBLE (-5600 4325);
FORCEPROP 1 LAST BODY_TYPE PLUMBING
J 0
(-5600 4275);
DISPLAY 1.595745 (-5600 4275);
PAINT GREEN (-5600 4275);
DISPLAY INVISIBLE (-5600 4275);
FORCEPROP 1 LAST HDL_TAP TRUE
J 0
(-5275 4200);
DISPLAY 1.595745 (-5275 4200);
PAINT GREEN (-5275 4200);
DISPLAY INVISIBLE (-5275 4200);
FORCEPROP 1 LAST PATH I79
J 0
(-5602 4325);
DISPLAY 0.872340 (-5602 4325);
PAINT GREEN (-5602 4325);
DISPLAY INVISIBLE (-5602 4325);
FORCEADD TAP..6
(-5600 725);
FORCEPROP 3 LASTPIN (-5550 725) SIG_NAME M_H_CLK_DN<2>
J 0
(-5540 735);
DISPLAY 0.659574 (-5540 735);
PAINT MONO (-5540 735);
DISPLAY INVISIBLE (-5540 735);
FORCEPROP 1 LASTPIN (-5550 725) BN 2
J 0
(-5602 733);
DISPLAY 0.617021 (-5602 733);
PAINT GREEN (-5602 733);
FORCEPROP 2 LAST CDS_LIB mstr_standard
J 0
(-5600 725);
PAINT MONO (-5600 725);
DISPLAY INVISIBLE (-5600 725);
FORCEPROP 1 LAST BODY_TYPE PLUMBING
J 0
(-5600 675);
DISPLAY 1.595745 (-5600 675);
PAINT GREEN (-5600 675);
DISPLAY INVISIBLE (-5600 675);
FORCEPROP 1 LAST HDL_TAP TRUE
J 0
(-5275 600);
DISPLAY 1.595745 (-5275 600);
PAINT GREEN (-5275 600);
DISPLAY INVISIBLE (-5275 600);
FORCEPROP 1 LAST PATH I8
J 0
(-5602 725);
DISPLAY 0.872340 (-5602 725);
PAINT GREEN (-5602 725);
DISPLAY INVISIBLE (-5602 725);
FORCEADD TAP..6
(-5600 4375);
FORCEPROP 3 LASTPIN (-5550 4375) SIG_NAME M_H_DQ<57>
J 0
(-5540 4385);
DISPLAY 0.659574 (-5540 4385);
PAINT MONO (-5540 4385);
DISPLAY INVISIBLE (-5540 4385);
FORCEPROP 1 LASTPIN (-5550 4375) BN 57
J 0
(-5602 4383);
DISPLAY 0.617021 (-5602 4383);
PAINT GREEN (-5602 4383);
FORCEPROP 2 LAST CDS_LIB mstr_standard
J 0
(-5600 4375);
PAINT MONO (-5600 4375);
DISPLAY INVISIBLE (-5600 4375);
FORCEPROP 1 LAST BODY_TYPE PLUMBING
J 0
(-5600 4325);
DISPLAY 1.595745 (-5600 4325);
PAINT GREEN (-5600 4325);
DISPLAY INVISIBLE (-5600 4325);
FORCEPROP 1 LAST HDL_TAP TRUE
J 0
(-5275 4250);
DISPLAY 1.595745 (-5275 4250);
PAINT GREEN (-5275 4250);
DISPLAY INVISIBLE (-5275 4250);
FORCEPROP 1 LAST PATH I80
J 0
(-5602 4375);
DISPLAY 0.872340 (-5602 4375);
PAINT GREEN (-5602 4375);
DISPLAY INVISIBLE (-5602 4375);
FORCEADD TAP..6
(-5600 4425);
FORCEPROP 3 LASTPIN (-5550 4425) SIG_NAME M_H_DQ<58>
J 0
(-5540 4435);
DISPLAY 0.659574 (-5540 4435);
PAINT MONO (-5540 4435);
DISPLAY INVISIBLE (-5540 4435);
FORCEPROP 1 LASTPIN (-5550 4425) BN 58
J 0
(-5602 4433);
DISPLAY 0.617021 (-5602 4433);
PAINT GREEN (-5602 4433);
FORCEPROP 2 LAST CDS_LIB mstr_standard
J 0
(-5600 4425);
PAINT MONO (-5600 4425);
DISPLAY INVISIBLE (-5600 4425);
FORCEPROP 1 LAST BODY_TYPE PLUMBING
J 0
(-5600 4375);
DISPLAY 1.595745 (-5600 4375);
PAINT GREEN (-5600 4375);
DISPLAY INVISIBLE (-5600 4375);
FORCEPROP 1 LAST HDL_TAP TRUE
J 0
(-5275 4300);
DISPLAY 1.595745 (-5275 4300);
PAINT GREEN (-5275 4300);
DISPLAY INVISIBLE (-5275 4300);
FORCEPROP 1 LAST PATH I81
J 0
(-5602 4425);
DISPLAY 0.872340 (-5602 4425);
PAINT GREEN (-5602 4425);
DISPLAY INVISIBLE (-5602 4425);
FORCEADD TAP..6
(-5600 4475);
FORCEPROP 3 LASTPIN (-5550 4475) SIG_NAME M_H_DQ<59>
J 0
(-5540 4485);
DISPLAY 0.659574 (-5540 4485);
PAINT MONO (-5540 4485);
DISPLAY INVISIBLE (-5540 4485);
FORCEPROP 1 LASTPIN (-5550 4475) BN 59
J 0
(-5602 4483);
DISPLAY 0.617021 (-5602 4483);
PAINT GREEN (-5602 4483);
FORCEPROP 2 LAST CDS_LIB mstr_standard
J 0
(-5600 4475);
PAINT MONO (-5600 4475);
DISPLAY INVISIBLE (-5600 4475);
FORCEPROP 1 LAST BODY_TYPE PLUMBING
J 0
(-5600 4425);
DISPLAY 1.595745 (-5600 4425);
PAINT GREEN (-5600 4425);
DISPLAY INVISIBLE (-5600 4425);
FORCEPROP 1 LAST HDL_TAP TRUE
J 0
(-5275 4350);
DISPLAY 1.595745 (-5275 4350);
PAINT GREEN (-5275 4350);
DISPLAY INVISIBLE (-5275 4350);
FORCEPROP 1 LAST PATH I82
J 0
(-5602 4475);
DISPLAY 0.872340 (-5602 4475);
PAINT GREEN (-5602 4475);
DISPLAY INVISIBLE (-5602 4475);
FORCEADD TAP..6
(-5600 4525);
FORCEPROP 3 LASTPIN (-5550 4525) SIG_NAME M_H_DQ<60>
J 0
(-5540 4535);
DISPLAY 0.659574 (-5540 4535);
PAINT MONO (-5540 4535);
DISPLAY INVISIBLE (-5540 4535);
FORCEPROP 1 LASTPIN (-5550 4525) BN 60
J 0
(-5602 4533);
DISPLAY 0.617021 (-5602 4533);
PAINT GREEN (-5602 4533);
FORCEPROP 2 LAST CDS_LIB mstr_standard
J 0
(-5600 4525);
PAINT MONO (-5600 4525);
DISPLAY INVISIBLE (-5600 4525);
FORCEPROP 1 LAST BODY_TYPE PLUMBING
J 0
(-5600 4475);
DISPLAY 1.595745 (-5600 4475);
PAINT GREEN (-5600 4475);
DISPLAY INVISIBLE (-5600 4475);
FORCEPROP 1 LAST HDL_TAP TRUE
J 0
(-5275 4400);
DISPLAY 1.595745 (-5275 4400);
PAINT GREEN (-5275 4400);
DISPLAY INVISIBLE (-5275 4400);
FORCEPROP 1 LAST PATH I83
J 0
(-5602 4525);
DISPLAY 0.872340 (-5602 4525);
PAINT GREEN (-5602 4525);
DISPLAY INVISIBLE (-5602 4525);
FORCEADD TAP..6
(-5600 4575);
FORCEPROP 3 LASTPIN (-5550 4575) SIG_NAME M_H_DQ<61>
J 0
(-5540 4585);
DISPLAY 0.659574 (-5540 4585);
PAINT MONO (-5540 4585);
DISPLAY INVISIBLE (-5540 4585);
FORCEPROP 1 LASTPIN (-5550 4575) BN 61
J 0
(-5602 4583);
DISPLAY 0.617021 (-5602 4583);
PAINT GREEN (-5602 4583);
FORCEPROP 2 LAST CDS_LIB mstr_standard
J 0
(-5600 4575);
PAINT MONO (-5600 4575);
DISPLAY INVISIBLE (-5600 4575);
FORCEPROP 1 LAST BODY_TYPE PLUMBING
J 0
(-5600 4525);
DISPLAY 1.595745 (-5600 4525);
PAINT GREEN (-5600 4525);
DISPLAY INVISIBLE (-5600 4525);
FORCEPROP 1 LAST HDL_TAP TRUE
J 0
(-5275 4450);
DISPLAY 1.595745 (-5275 4450);
PAINT GREEN (-5275 4450);
DISPLAY INVISIBLE (-5275 4450);
FORCEPROP 1 LAST PATH I84
J 0
(-5602 4575);
DISPLAY 0.872340 (-5602 4575);
PAINT GREEN (-5602 4575);
DISPLAY INVISIBLE (-5602 4575);
FORCEADD TAP..6
(-5600 4625);
FORCEPROP 3 LASTPIN (-5550 4625) SIG_NAME M_H_DQ<62>
J 0
(-5540 4635);
DISPLAY 0.659574 (-5540 4635);
PAINT MONO (-5540 4635);
DISPLAY INVISIBLE (-5540 4635);
FORCEPROP 1 LASTPIN (-5550 4625) BN 62
J 0
(-5602 4633);
DISPLAY 0.617021 (-5602 4633);
PAINT GREEN (-5602 4633);
FORCEPROP 2 LAST CDS_LIB mstr_standard
J 0
(-5600 4625);
PAINT MONO (-5600 4625);
DISPLAY INVISIBLE (-5600 4625);
FORCEPROP 1 LAST BODY_TYPE PLUMBING
J 0
(-5600 4575);
DISPLAY 1.595745 (-5600 4575);
PAINT GREEN (-5600 4575);
DISPLAY INVISIBLE (-5600 4575);
FORCEPROP 1 LAST HDL_TAP TRUE
J 0
(-5275 4500);
DISPLAY 1.595745 (-5275 4500);
PAINT GREEN (-5275 4500);
DISPLAY INVISIBLE (-5275 4500);
FORCEPROP 1 LAST PATH I85
J 0
(-5602 4625);
DISPLAY 0.872340 (-5602 4625);
PAINT GREEN (-5602 4625);
DISPLAY INVISIBLE (-5602 4625);
FORCEADD TAP..6
(-5600 4675);
FORCEPROP 3 LASTPIN (-5550 4675) SIG_NAME M_H_DQ<63>
J 0
(-5540 4685);
DISPLAY 0.659574 (-5540 4685);
PAINT MONO (-5540 4685);
DISPLAY INVISIBLE (-5540 4685);
FORCEPROP 1 LASTPIN (-5550 4675) BN 63
J 0
(-5602 4683);
DISPLAY 0.617021 (-5602 4683);
PAINT GREEN (-5602 4683);
FORCEPROP 2 LAST CDS_LIB mstr_standard
J 0
(-5600 4675);
PAINT MONO (-5600 4675);
DISPLAY INVISIBLE (-5600 4675);
FORCEPROP 1 LAST BODY_TYPE PLUMBING
J 0
(-5600 4625);
DISPLAY 1.595745 (-5600 4625);
PAINT GREEN (-5600 4625);
DISPLAY INVISIBLE (-5600 4625);
FORCEPROP 1 LAST HDL_TAP TRUE
J 0
(-5275 4550);
DISPLAY 1.595745 (-5275 4550);
PAINT GREEN (-5275 4550);
DISPLAY INVISIBLE (-5275 4550);
FORCEPROP 1 LAST PATH I86
J 0
(-5602 4675);
DISPLAY 0.872340 (-5602 4675);
PAINT GREEN (-5602 4675);
DISPLAY INVISIBLE (-5602 4675);
FORCEADD TAP..6
R 2
(-2875 775);
FORCEPROP 3 LASTPIN (-2925 775) SIG_NAME M_H_BA<1>
J 0
(-2915 785);
DISPLAY 0.659574 (-2915 785);
PAINT MONO (-2915 785);
DISPLAY INVISIBLE (-2915 785);
FORCEPROP 1 LASTPIN (-2925 775) BN 1
J 2
(-2873 783);
DISPLAY 0.617021 (-2873 783);
PAINT GREEN (-2873 783);
FORCEPROP 2 LAST CDS_LIB mstr_standard
J 0
(-2875 775);
PAINT MONO (-2875 775);
DISPLAY INVISIBLE (-2875 775);
FORCEPROP 1 LAST BODY_TYPE PLUMBING
J 2
(-2875 725);
DISPLAY 1.595745 (-2875 725);
PAINT GREEN (-2875 725);
DISPLAY INVISIBLE (-2875 725);
FORCEPROP 1 LAST HDL_TAP TRUE
J 2
(-3200 650);
DISPLAY 1.595745 (-3200 650);
PAINT GREEN (-3200 650);
DISPLAY INVISIBLE (-3200 650);
FORCEPROP 1 LAST PATH I87
J 2
(-2873 775);
DISPLAY 0.872340 (-2873 775);
PAINT GREEN (-2873 775);
DISPLAY INVISIBLE (-2873 775);
FORCEADD TAP..6
R 2
(-2875 725);
FORCEPROP 3 LASTPIN (-2925 725) SIG_NAME M_H_BA<0>
J 0
(-2915 735);
DISPLAY 0.659574 (-2915 735);
PAINT MONO (-2915 735);
DISPLAY INVISIBLE (-2915 735);
FORCEPROP 1 LASTPIN (-2925 725) BN 0
J 2
(-2873 733);
DISPLAY 0.617021 (-2873 733);
PAINT GREEN (-2873 733);
FORCEPROP 2 LAST CDS_LIB mstr_standard
J 0
(-2875 725);
PAINT MONO (-2875 725);
DISPLAY INVISIBLE (-2875 725);
FORCEPROP 1 LAST BODY_TYPE PLUMBING
J 2
(-2875 675);
DISPLAY 1.595745 (-2875 675);
PAINT GREEN (-2875 675);
DISPLAY INVISIBLE (-2875 675);
FORCEPROP 1 LAST HDL_TAP TRUE
J 2
(-3200 600);
DISPLAY 1.595745 (-3200 600);
PAINT GREEN (-3200 600);
DISPLAY INVISIBLE (-3200 600);
FORCEPROP 1 LAST PATH I88
J 2
(-2873 725);
DISPLAY 0.872340 (-2873 725);
PAINT GREEN (-2873 725);
DISPLAY INVISIBLE (-2873 725);
FORCEADD TAP..6
R 2
(-2875 825);
FORCEPROP 3 LASTPIN (-2925 825) SIG_NAME M_H_BG<0>
J 0
(-2915 835);
DISPLAY 0.659574 (-2915 835);
PAINT MONO (-2915 835);
DISPLAY INVISIBLE (-2915 835);
FORCEPROP 1 LASTPIN (-2925 825) BN 0
J 2
(-2873 833);
DISPLAY 0.617021 (-2873 833);
PAINT GREEN (-2873 833);
FORCEPROP 2 LAST CDS_LIB mstr_standard
J 0
(-2875 825);
PAINT MONO (-2875 825);
DISPLAY INVISIBLE (-2875 825);
FORCEPROP 1 LAST BODY_TYPE PLUMBING
J 2
(-2875 775);
DISPLAY 1.595745 (-2875 775);
PAINT GREEN (-2875 775);
DISPLAY INVISIBLE (-2875 775);
FORCEPROP 1 LAST HDL_TAP TRUE
J 2
(-3200 700);
DISPLAY 1.595745 (-3200 700);
PAINT GREEN (-3200 700);
DISPLAY INVISIBLE (-3200 700);
FORCEPROP 1 LAST PATH I89
J 2
(-2873 825);
DISPLAY 0.872340 (-2873 825);
PAINT GREEN (-2873 825);
DISPLAY INVISIBLE (-2873 825);
FORCEADD TAP..6
(-5600 875);
FORCEPROP 3 LASTPIN (-5550 875) SIG_NAME M_H_CLK_DP<1>
J 0
(-5540 885);
DISPLAY 0.659574 (-5540 885);
PAINT MONO (-5540 885);
DISPLAY INVISIBLE (-5540 885);
FORCEPROP 1 LASTPIN (-5550 875) BN 1
J 0
(-5602 883);
DISPLAY 0.617021 (-5602 883);
PAINT GREEN (-5602 883);
FORCEPROP 2 LAST CDS_LIB mstr_standard
J 0
(-5600 875);
PAINT MONO (-5600 875);
DISPLAY INVISIBLE (-5600 875);
FORCEPROP 1 LAST BODY_TYPE PLUMBING
J 0
(-5600 825);
DISPLAY 1.595745 (-5600 825);
PAINT GREEN (-5600 825);
DISPLAY INVISIBLE (-5600 825);
FORCEPROP 1 LAST HDL_TAP TRUE
J 0
(-5275 750);
DISPLAY 1.595745 (-5275 750);
PAINT GREEN (-5275 750);
DISPLAY INVISIBLE (-5275 750);
FORCEPROP 1 LAST PATH I9
J 0
(-5602 875);
DISPLAY 0.872340 (-5602 875);
PAINT GREEN (-5602 875);
DISPLAY INVISIBLE (-5602 875);
FORCEADD TAP..6
R 2
(-2875 875);
FORCEPROP 3 LASTPIN (-2925 875) SIG_NAME M_H_BG<1>
J 0
(-2915 885);
DISPLAY 0.659574 (-2915 885);
PAINT MONO (-2915 885);
DISPLAY INVISIBLE (-2915 885);
FORCEPROP 1 LASTPIN (-2925 875) BN 1
J 2
(-2873 883);
DISPLAY 0.617021 (-2873 883);
PAINT GREEN (-2873 883);
FORCEPROP 2 LAST CDS_LIB mstr_standard
J 0
(-2875 875);
PAINT MONO (-2875 875);
DISPLAY INVISIBLE (-2875 875);
FORCEPROP 1 LAST BODY_TYPE PLUMBING
J 2
(-2875 825);
DISPLAY 1.595745 (-2875 825);
PAINT GREEN (-2875 825);
DISPLAY INVISIBLE (-2875 825);
FORCEPROP 1 LAST HDL_TAP TRUE
J 2
(-3200 750);
DISPLAY 1.595745 (-3200 750);
PAINT GREEN (-3200 750);
DISPLAY INVISIBLE (-3200 750);
FORCEPROP 1 LAST PATH I90
J 2
(-2873 875);
DISPLAY 0.872340 (-2873 875);
PAINT GREEN (-2873 875);
DISPLAY INVISIBLE (-2873 875);
FORCEADD TAP..6
R 2
(-2875 1075);
FORCEPROP 3 LASTPIN (-2925 1075) SIG_NAME M_H_CS_N<2>
J 0
(-2915 1085);
DISPLAY 0.659574 (-2915 1085);
PAINT MONO (-2915 1085);
DISPLAY INVISIBLE (-2915 1085);
FORCEPROP 1 LASTPIN (-2925 1075) BN 2
J 2
(-2873 1083);
DISPLAY 0.617021 (-2873 1083);
PAINT GREEN (-2873 1083);
FORCEPROP 2 LAST CDS_LIB mstr_standard
J 0
(-2875 1075);
PAINT MONO (-2875 1075);
DISPLAY INVISIBLE (-2875 1075);
FORCEPROP 1 LAST BODY_TYPE PLUMBING
J 2
(-2875 1025);
DISPLAY 1.595745 (-2875 1025);
PAINT GREEN (-2875 1025);
DISPLAY INVISIBLE (-2875 1025);
FORCEPROP 1 LAST HDL_TAP TRUE
J 2
(-3200 950);
DISPLAY 1.595745 (-3200 950);
PAINT GREEN (-3200 950);
DISPLAY INVISIBLE (-3200 950);
FORCEPROP 1 LAST PATH I91
J 2
(-2873 1075);
DISPLAY 0.872340 (-2873 1075);
PAINT GREEN (-2873 1075);
DISPLAY INVISIBLE (-2873 1075);
FORCEADD TAP..6
R 2
(-2875 1025);
FORCEPROP 3 LASTPIN (-2925 1025) SIG_NAME M_H_CS_N<1>
J 0
(-2915 1035);
DISPLAY 0.659574 (-2915 1035);
PAINT MONO (-2915 1035);
DISPLAY INVISIBLE (-2915 1035);
FORCEPROP 1 LASTPIN (-2925 1025) BN 1
J 2
(-2873 1033);
DISPLAY 0.617021 (-2873 1033);
PAINT GREEN (-2873 1033);
FORCEPROP 2 LAST CDS_LIB mstr_standard
J 0
(-2875 1025);
PAINT MONO (-2875 1025);
DISPLAY INVISIBLE (-2875 1025);
FORCEPROP 1 LAST BODY_TYPE PLUMBING
J 2
(-2875 975);
DISPLAY 1.595745 (-2875 975);
PAINT GREEN (-2875 975);
DISPLAY INVISIBLE (-2875 975);
FORCEPROP 1 LAST HDL_TAP TRUE
J 2
(-3200 900);
DISPLAY 1.595745 (-3200 900);
PAINT GREEN (-3200 900);
DISPLAY INVISIBLE (-3200 900);
FORCEPROP 1 LAST PATH I92
J 2
(-2873 1025);
DISPLAY 0.872340 (-2873 1025);
PAINT GREEN (-2873 1025);
DISPLAY INVISIBLE (-2873 1025);
FORCEADD TAP..6
R 2
(-2875 975);
FORCEPROP 3 LASTPIN (-2925 975) SIG_NAME M_H_CS_N<0>
J 0
(-2915 985);
DISPLAY 0.659574 (-2915 985);
PAINT MONO (-2915 985);
DISPLAY INVISIBLE (-2915 985);
FORCEPROP 1 LASTPIN (-2925 975) BN 0
J 2
(-2873 983);
DISPLAY 0.617021 (-2873 983);
PAINT GREEN (-2873 983);
FORCEPROP 2 LAST CDS_LIB mstr_standard
J 0
(-2875 975);
PAINT MONO (-2875 975);
DISPLAY INVISIBLE (-2875 975);
FORCEPROP 1 LAST BODY_TYPE PLUMBING
J 2
(-2875 925);
DISPLAY 1.595745 (-2875 925);
PAINT GREEN (-2875 925);
DISPLAY INVISIBLE (-2875 925);
FORCEPROP 1 LAST HDL_TAP TRUE
J 2
(-3200 850);
DISPLAY 1.595745 (-3200 850);
PAINT GREEN (-3200 850);
DISPLAY INVISIBLE (-3200 850);
FORCEPROP 1 LAST PATH I93
J 2
(-2873 975);
DISPLAY 0.872340 (-2873 975);
PAINT GREEN (-2873 975);
DISPLAY INVISIBLE (-2873 975);
FORCEADD TAP..6
R 2
(-2875 1175);
FORCEPROP 3 LASTPIN (-2925 1175) SIG_NAME M_H_CS_N<4>
J 0
(-2915 1185);
DISPLAY 0.659574 (-2915 1185);
PAINT MONO (-2915 1185);
DISPLAY INVISIBLE (-2915 1185);
FORCEPROP 1 LASTPIN (-2925 1175) BN 4
J 2
(-2873 1183);
DISPLAY 0.617021 (-2873 1183);
PAINT GREEN (-2873 1183);
FORCEPROP 2 LAST CDS_LIB mstr_standard
J 0
(-2875 1175);
PAINT MONO (-2875 1175);
DISPLAY INVISIBLE (-2875 1175);
FORCEPROP 1 LAST BODY_TYPE PLUMBING
J 2
(-2875 1125);
DISPLAY 1.595745 (-2875 1125);
PAINT GREEN (-2875 1125);
DISPLAY INVISIBLE (-2875 1125);
FORCEPROP 1 LAST HDL_TAP TRUE
J 2
(-3200 1050);
DISPLAY 1.595745 (-3200 1050);
PAINT GREEN (-3200 1050);
DISPLAY INVISIBLE (-3200 1050);
FORCEPROP 1 LAST PATH I94
J 2
(-2873 1175);
DISPLAY 0.872340 (-2873 1175);
PAINT GREEN (-2873 1175);
DISPLAY INVISIBLE (-2873 1175);
FORCEADD TAP..6
R 2
(-2875 1125);
FORCEPROP 3 LASTPIN (-2925 1125) SIG_NAME M_H_CS_N<3>
J 0
(-2915 1135);
DISPLAY 0.659574 (-2915 1135);
PAINT MONO (-2915 1135);
DISPLAY INVISIBLE (-2915 1135);
FORCEPROP 1 LASTPIN (-2925 1125) BN 3
J 2
(-2873 1133);
DISPLAY 0.617021 (-2873 1133);
PAINT GREEN (-2873 1133);
FORCEPROP 2 LAST CDS_LIB mstr_standard
J 0
(-2875 1125);
PAINT MONO (-2875 1125);
DISPLAY INVISIBLE (-2875 1125);
FORCEPROP 1 LAST BODY_TYPE PLUMBING
J 2
(-2875 1075);
DISPLAY 1.595745 (-2875 1075);
PAINT GREEN (-2875 1075);
DISPLAY INVISIBLE (-2875 1075);
FORCEPROP 1 LAST HDL_TAP TRUE
J 2
(-3200 1000);
DISPLAY 1.595745 (-3200 1000);
PAINT GREEN (-3200 1000);
DISPLAY INVISIBLE (-3200 1000);
FORCEPROP 1 LAST PATH I95
J 2
(-2873 1125);
DISPLAY 0.872340 (-2873 1125);
PAINT GREEN (-2873 1125);
DISPLAY INVISIBLE (-2873 1125);
FORCEADD TAP..6
R 2
(-2875 1225);
FORCEPROP 3 LASTPIN (-2925 1225) SIG_NAME M_H_CS_N<5>
J 0
(-2915 1235);
DISPLAY 0.659574 (-2915 1235);
PAINT MONO (-2915 1235);
DISPLAY INVISIBLE (-2915 1235);
FORCEPROP 1 LASTPIN (-2925 1225) BN 5
J 2
(-2873 1233);
DISPLAY 0.617021 (-2873 1233);
PAINT GREEN (-2873 1233);
FORCEPROP 2 LAST CDS_LIB mstr_standard
J 0
(-2875 1225);
PAINT MONO (-2875 1225);
DISPLAY INVISIBLE (-2875 1225);
FORCEPROP 1 LAST BODY_TYPE PLUMBING
J 2
(-2875 1175);
DISPLAY 1.595745 (-2875 1175);
PAINT GREEN (-2875 1175);
DISPLAY INVISIBLE (-2875 1175);
FORCEPROP 1 LAST HDL_TAP TRUE
J 2
(-3200 1100);
DISPLAY 1.595745 (-3200 1100);
PAINT GREEN (-3200 1100);
DISPLAY INVISIBLE (-3200 1100);
FORCEPROP 1 LAST PATH I96
J 2
(-2873 1225);
DISPLAY 0.872340 (-2873 1225);
PAINT GREEN (-2873 1225);
DISPLAY INVISIBLE (-2873 1225);
FORCEADD TAP..6
R 2
(-2875 1275);
FORCEPROP 3 LASTPIN (-2925 1275) SIG_NAME M_H_CS_N<6>
J 0
(-2915 1285);
DISPLAY 0.659574 (-2915 1285);
PAINT MONO (-2915 1285);
DISPLAY INVISIBLE (-2915 1285);
FORCEPROP 1 LASTPIN (-2925 1275) BN 6
J 2
(-2873 1283);
DISPLAY 0.617021 (-2873 1283);
PAINT GREEN (-2873 1283);
FORCEPROP 2 LAST CDS_LIB mstr_standard
J 0
(-2875 1275);
PAINT MONO (-2875 1275);
DISPLAY INVISIBLE (-2875 1275);
FORCEPROP 1 LAST BODY_TYPE PLUMBING
J 2
(-2875 1225);
DISPLAY 1.595745 (-2875 1225);
PAINT GREEN (-2875 1225);
DISPLAY INVISIBLE (-2875 1225);
FORCEPROP 1 LAST HDL_TAP TRUE
J 2
(-3200 1150);
DISPLAY 1.595745 (-3200 1150);
PAINT GREEN (-3200 1150);
DISPLAY INVISIBLE (-3200 1150);
FORCEPROP 1 LAST PATH I97
J 2
(-2873 1275);
DISPLAY 0.872340 (-2873 1275);
PAINT GREEN (-2873 1275);
DISPLAY INVISIBLE (-2873 1275);
FORCEADD TAP..6
R 2
(-2875 1325);
FORCEPROP 3 LASTPIN (-2925 1325) SIG_NAME M_H_CS_N<7>
J 0
(-2915 1335);
DISPLAY 0.659574 (-2915 1335);
PAINT MONO (-2915 1335);
DISPLAY INVISIBLE (-2915 1335);
FORCEPROP 1 LASTPIN (-2925 1325) BN 7
J 2
(-2873 1333);
DISPLAY 0.617021 (-2873 1333);
PAINT GREEN (-2873 1333);
FORCEPROP 2 LAST CDS_LIB mstr_standard
J 0
(-2875 1325);
PAINT MONO (-2875 1325);
DISPLAY INVISIBLE (-2875 1325);
FORCEPROP 1 LAST BODY_TYPE PLUMBING
J 2
(-2875 1275);
DISPLAY 1.595745 (-2875 1275);
PAINT GREEN (-2875 1275);
DISPLAY INVISIBLE (-2875 1275);
FORCEPROP 1 LAST HDL_TAP TRUE
J 2
(-3200 1200);
DISPLAY 1.595745 (-3200 1200);
PAINT GREEN (-3200 1200);
DISPLAY INVISIBLE (-3200 1200);
FORCEPROP 1 LAST PATH I98
J 2
(-2873 1325);
DISPLAY 0.872340 (-2873 1325);
PAINT GREEN (-2873 1325);
DISPLAY INVISIBLE (-2873 1325);
FORCEADD TAP..6
R 2
(-2875 1425);
FORCEPROP 3 LASTPIN (-2925 1425) SIG_NAME M_H_ODT<0>
J 0
(-2915 1435);
DISPLAY 0.659574 (-2915 1435);
PAINT MONO (-2915 1435);
DISPLAY INVISIBLE (-2915 1435);
FORCEPROP 1 LASTPIN (-2925 1425) BN 0
J 2
(-2873 1433);
DISPLAY 0.617021 (-2873 1433);
PAINT GREEN (-2873 1433);
FORCEPROP 2 LAST CDS_LIB mstr_standard
J 0
(-2875 1425);
PAINT MONO (-2875 1425);
DISPLAY INVISIBLE (-2875 1425);
FORCEPROP 1 LAST BODY_TYPE PLUMBING
J 2
(-2875 1375);
DISPLAY 1.595745 (-2875 1375);
PAINT GREEN (-2875 1375);
DISPLAY INVISIBLE (-2875 1375);
FORCEPROP 1 LAST HDL_TAP TRUE
J 2
(-3200 1300);
DISPLAY 1.595745 (-3200 1300);
PAINT GREEN (-3200 1300);
DISPLAY INVISIBLE (-3200 1300);
FORCEPROP 1 LAST PATH I99
J 2
(-2873 1425);
DISPLAY 0.872340 (-2873 1425);
PAINT GREEN (-2873 1425);
DISPLAY INVISIBLE (-2873 1425);
FORCEADD DESIGN_NOTE..1
(-6225 375);
FORCEPROP 0 LAST L1 CPU SYMBOLS 1-30 ARE PRELIMINARY AND SUBJECT TO CHANGE
J 0
(-6425 250);
DISPLAY 1.021277 (-6425 250);
PAINT ORANGE (-6425 250);
FORCEPROP 2 LAST CDS_LIB mstr_symbols
J 0
(-6225 375);
PAINT ORANGE (-6225 375);
DISPLAY INVISIBLE (-6225 375);
FORCEPROP 1 LAST COMMENT_BODY TRUE
J 0
(-6200 475);
DISPLAY 0.978723 (-6200 475);
PAINT ORANGE (-6200 475);
DISPLAY INVISIBLE (-6200 475);
FORCEADD PRELIM..10
(-4240 2565);
PAINT GRAY (-4240 2565);
FORCEPROP 2 LAST CDS_LIB mstr_misc
J 0
(-4240 2565);
PAINT ORANGE (-4240 2565);
DISPLAY INVISIBLE (-4240 2565);
FORCEPROP 1 LAST COMMENT_BODY TRUE
J 0
(-4240 2565);
PAINT ORANGE (-4240 2565);
DISPLAY INVISIBLE (-4240 2565);
FORCEADD INTEL_CORP_BPAGE..1
(0 0);
FORCEPROP 1 LAST CDS_CON_LAST_MODIFIED Tue Dec 01 11:51:34 2015
J 0
(-1425 325);
DISPLAY 1.340426 (-1425 325);
PAINT GREEN (-1425 325);
DISPLAY INVISIBLE (-1425 325);
FORCEPROP 1 LAST CUSTOM_TXT_CDS <CURRENT_DESIGN_SHEET> OF <TOTAL_DESIGN_SHEETS>
J 0
(-500 25);
PAINT GREEN (-500 25);
FORCEPROP 1 LAST CUSTOM_TXT_CDS <CON_LAST_MODIFIED>
J 0
(-1925 350);
PAINT GREEN (-1925 350);
FORCEPROP 2 LAST CUSTOM_TXT_CDS <XR_PAGE_TITLE>
J 0
(-7890 5250);
DISPLAY 0.638298 (-7890 5250);
PAINT PINK (-7890 5250);
DISPLAY INVISIBLE (-7890 5250);
FORCEPROP 1 LAST SCH_ADDRESS3 Santa Clara, CA 95052-8119
J 0
(-3975 25);
DISPLAY 0.617021 (-3975 25);
PAINT GREEN (-3975 25);
FORCEPROP 1 LAST SCH_ADDRESS2 P.O. BOX 58119
J 0
(-3975 75);
DISPLAY 0.617021 (-3975 75);
PAINT GREEN (-3975 75);
FORCEPROP 1 LAST SCH_ADDRESS1 2200 Mission College Blvd.
J 0
(-3975 125);
DISPLAY 0.617021 (-3975 125);
PAINT GREEN (-3975 125);
FORCEPROP 1 LAST SCH_TITLE SKYLAKE - SKT1 - 4 OF 21
J 0
(-7950 50);
DISPLAY 1.212766 (-7950 50);
PAINT GREEN (-7950 50);
FORCEPROP 1 LAST SCH_NUMBER H4694802
J 0
(-1300 150);
DISPLAY 1.212766 (-1300 150);
PAINT YELLOW (-1300 150);
FORCEPROP 1 LAST SCH_DEPT BESD
J 1
(-4450 100);
DISPLAY 1.212766 (-4450 100);
PAINT YELLOW (-4450 100);
FORCEPROP 1 LAST SCH_REV 2.420
J 0
(-250 150);
DISPLAY 0.978723 (-250 150);
PAINT YELLOW (-250 150);
FORCEPROP 2 LAST PAGE_BORDER TRUE
J 0
(-7890 5250);
DISPLAY 0.851064 (-7890 5250);
PAINT PINK (-7890 5250);
DISPLAY INVISIBLE (-7890 5250);
FORCEPROP 2 LAST CDS_LIB mstr_symbols
J 0
(0 0);
PAINT ORANGE (0 0);
DISPLAY INVISIBLE (0 0);
FORCEPROP 1 LAST COMMENT_BODY TRUE
J 0
(12 12);
DISPLAY 0.638298 (12 12);
PAINT GREEN (12 12);
DISPLAY INVISIBLE (12 12);
FORCEPROP 2 LAST CDS_XR_PAGE_TITLE CR-58 : @BASEBOARD_FAB2_LIB.BASEBOARD_FAB2(SCH_1):PAGE58
J 0
(-7890 5250);
DISPLAY 0.638298 (-7890 5250);
PAINT PINK (-7890 5250);
DISPLAY INVISIBLE (-7890 5250);
WIRE 17 -1 (-2825 4700)(-2825 4750);
WIRE 17 -1 (-2825 4650)(-2825 4700);
WIRE 17 -1 (-2075 4750)(-2825 4750);
FORCEPROP 2 LAST SIG_NAME M_H_DQS_DP<17:0>
J 0
(-2725 4760);
DISPLAY 0.617021 (-2725 4760);
PAINT ORANGE (-2725 4760);
WIRE 17 -1 (-2825 4600)(-2825 4650);
WIRE 17 -1 (-2825 4550)(-2825 4600);
WIRE 17 -1 (-2825 4500)(-2825 4550);
WIRE 17 -1 (-2825 4450)(-2825 4500);
WIRE 17 -1 (-2825 4400)(-2825 4450);
WIRE 17 -1 (-2825 4350)(-2825 4400);
WIRE 17 -1 (-2825 4300)(-2825 4350);
WIRE 17 -1 (-2825 4250)(-2825 4300);
WIRE 17 -1 (-2825 4200)(-2825 4250);
WIRE 17 -1 (-2825 4150)(-2825 4200);
WIRE 17 -1 (-2825 4100)(-2825 4150);
WIRE 17 -1 (-2825 4050)(-2825 4100);
WIRE 17 -1 (-2825 4000)(-2825 4050);
WIRE 17 -1 (-2825 3950)(-2825 4000);
WIRE 17 -1 (-2825 3900)(-2825 3950);
WIRE 17 -1 (-2825 3850)(-2825 3900);
WIRE 17 -1 (-2825 3750)(-2825 3775);
WIRE 17 -1 (-2825 3700)(-2825 3750);
WIRE 17 -1 (-2075 3775)(-2825 3775);
FORCEPROP 2 LAST SIG_NAME M_H_DQS_DN<17:0>
J 0
(-2725 3785);
DISPLAY 0.617021 (-2725 3785);
PAINT ORANGE (-2725 3785);
WIRE 17 -1 (-2825 3650)(-2825 3700);
WIRE 17 -1 (-2825 3600)(-2825 3650);
WIRE 17 -1 (-2825 3550)(-2825 3600);
WIRE 17 -1 (-2825 3500)(-2825 3550);
WIRE 17 -1 (-2825 3450)(-2825 3500);
WIRE 17 -1 (-2825 3400)(-2825 3450);
WIRE 17 -1 (-2825 3350)(-2825 3400);
WIRE 17 -1 (-2825 3300)(-2825 3350);
WIRE 17 -1 (-2825 3250)(-2825 3300);
WIRE 17 -1 (-2825 3200)(-2825 3250);
WIRE 17 -1 (-2825 3150)(-2825 3200);
WIRE 17 -1 (-2825 3100)(-2825 3150);
WIRE 17 -1 (-2825 3050)(-2825 3100);
WIRE 17 -1 (-2825 3000)(-2825 3050);
WIRE 17 -1 (-2825 2950)(-2825 3000);
WIRE 17 -1 (-2825 2900)(-2825 2950);
WIRE 17 -1 (-2825 2800)(-2825 2825);
WIRE 17 -1 (-2825 2750)(-2825 2800);
WIRE 17 -1 (-2075 2825)(-2825 2825);
FORCEPROP 2 LAST SIG_NAME M_H_MA<17:0>
J 0
(-2725 2835);
DISPLAY 0.617021 (-2725 2835);
PAINT ORANGE (-2725 2835);
WIRE 17 -1 (-2825 2700)(-2825 2750);
WIRE 17 -1 (-2825 2650)(-2825 2700);
WIRE 17 -1 (-2825 2600)(-2825 2650);
WIRE 17 -1 (-2825 2550)(-2825 2600);
WIRE 17 -1 (-2825 2500)(-2825 2550);
WIRE 17 -1 (-2825 2450)(-2825 2500);
WIRE 17 -1 (-2825 2400)(-2825 2450);
WIRE 17 -1 (-2825 2350)(-2825 2400);
WIRE 17 -1 (-2825 2300)(-2825 2350);
WIRE 17 -1 (-2825 2250)(-2825 2300);
WIRE 17 -1 (-2825 2200)(-2825 2250);
WIRE 17 -1 (-2825 2150)(-2825 2200);
WIRE 17 -1 (-2825 2100)(-2825 2150);
WIRE 17 -1 (-2825 2050)(-2825 2100);
WIRE 17 -1 (-2825 2000)(-2825 2050);
WIRE 17 -1 (-2825 1950)(-2825 2000);
WIRE 17 -1 (-2825 800)(-2825 825);
WIRE 17 -1 (-2825 750)(-2825 800);
WIRE 17 -1 (-2075 825)(-2825 825);
FORCEPROP 2 LAST SIG_NAME M_H_BA<1:0>
J 0
(-2725 835);
DISPLAY 0.617021 (-2725 835);
PAINT ORANGE (-2725 835);
WIRE 17 -1 (-2825 900)(-2825 925);
WIRE 17 -1 (-2825 850)(-2825 900);
WIRE 17 -1 (-2075 925)(-2825 925);
FORCEPROP 2 LAST SIG_NAME M_H_BG<1:0>
J 0
(-2725 935);
DISPLAY 0.617021 (-2725 935);
PAINT ORANGE (-2725 935);
WIRE 17 -1 (-2825 1850)(-2825 1875);
WIRE 17 -1 (-2825 1800)(-2825 1850);
WIRE 17 -1 (-2075 1875)(-2825 1875);
FORCEPROP 2 LAST SIG_NAME M_H_CKE<3:0>
J 0
(-2725 1885);
DISPLAY 0.617021 (-2725 1885);
PAINT ORANGE (-2725 1885);
WIRE 17 -1 (-2825 1750)(-2825 1800);
WIRE 17 -1 (-2825 1700)(-2825 1750);
WIRE 17 -1 (-2825 1350)(-2825 1375);
WIRE 17 -1 (-2825 1300)(-2825 1350);
WIRE 17 -1 (-2075 1375)(-2825 1375);
FORCEPROP 2 LAST SIG_NAME M_H_CS_N<7:0>
J 0
(-2725 1385);
DISPLAY 0.617021 (-2725 1385);
PAINT ORANGE (-2725 1385);
WIRE 17 -1 (-2825 1250)(-2825 1300);
WIRE 17 -1 (-2825 1200)(-2825 1250);
WIRE 17 -1 (-2825 1150)(-2825 1200);
WIRE 17 -1 (-2825 1100)(-2825 1150);
WIRE 17 -1 (-2825 1050)(-2825 1100);
WIRE 17 -1 (-2825 1000)(-2825 1050);
WIRE 17 -1 (-2825 1600)(-2825 1625);
WIRE 17 -1 (-2825 1550)(-2825 1600);
WIRE 17 -1 (-2075 1625)(-2825 1625);
FORCEPROP 2 LAST SIG_NAME M_H_ODT<3:0>
J 0
(-2725 1635);
DISPLAY 0.617021 (-2725 1635);
PAINT ORANGE (-2725 1635);
WIRE 17 -1 (-2825 1500)(-2825 1550);
WIRE 17 -1 (-2825 1450)(-2825 1500);
WIRE 17 -1 (-5650 4650)(-5650 4700);
WIRE 17 -1 (-5650 4600)(-5650 4650);
WIRE 17 -1 (-5650 4700)(-5650 4800);
WIRE 17 -1 (-5650 4800)(-6400 4800);
FORCEPROP 2 LAST SIG_NAME M_H_DQ<63:0>
J 0
(-6350 4810);
DISPLAY 0.617021 (-6350 4810);
PAINT ORANGE (-6350 4810);
WIRE 17 -1 (-5650 4550)(-5650 4600);
WIRE 17 -1 (-5650 4500)(-5650 4550);
WIRE 17 -1 (-5650 4450)(-5650 4500);
WIRE 17 -1 (-5650 4400)(-5650 4450);
WIRE 17 -1 (-5650 4350)(-5650 4400);
WIRE 17 -1 (-5650 4300)(-5650 4350);
WIRE 17 -1 (-5650 4250)(-5650 4300);
WIRE 17 -1 (-5650 4200)(-5650 4250);
WIRE 17 -1 (-5650 4150)(-5650 4200);
WIRE 17 -1 (-5650 4100)(-5650 4150);
WIRE 17 -1 (-5650 4050)(-5650 4100);
WIRE 17 -1 (-5650 4000)(-5650 4050);
WIRE 17 -1 (-5650 3950)(-5650 4000);
WIRE 17 -1 (-5650 3900)(-5650 3950);
WIRE 17 -1 (-5650 3850)(-5650 3900);
WIRE 17 -1 (-5650 3800)(-5650 3850);
WIRE 17 -1 (-5650 3750)(-5650 3800);
WIRE 17 -1 (-5650 3700)(-5650 3750);
WIRE 17 -1 (-5650 3650)(-5650 3700);
WIRE 17 -1 (-5650 3600)(-5650 3650);
WIRE 17 -1 (-5650 3550)(-5650 3600);
WIRE 17 -1 (-5650 3500)(-5650 3550);
WIRE 17 -1 (-5650 3450)(-5650 3500);
WIRE 17 -1 (-5650 3400)(-5650 3450);
WIRE 17 -1 (-5650 3350)(-5650 3400);
WIRE 17 -1 (-5650 3300)(-5650 3350);
WIRE 17 -1 (-5650 3250)(-5650 3300);
WIRE 17 -1 (-5650 3200)(-5650 3250);
WIRE 17 -1 (-5650 3150)(-5650 3200);
WIRE 17 -1 (-5650 3100)(-5650 3150);
WIRE 17 -1 (-5650 3050)(-5650 3100);
WIRE 17 -1 (-5650 3000)(-5650 3050);
WIRE 17 -1 (-5650 2950)(-5650 3000);
WIRE 17 -1 (-5650 2900)(-5650 2950);
WIRE 17 -1 (-5650 2850)(-5650 2900);
WIRE 17 -1 (-5650 2800)(-5650 2850);
WIRE 17 -1 (-5650 2750)(-5650 2800);
WIRE 17 -1 (-5650 2700)(-5650 2750);
WIRE 17 -1 (-5650 2650)(-5650 2700);
WIRE 17 -1 (-5650 2600)(-5650 2650);
WIRE 17 -1 (-5650 2550)(-5650 2600);
WIRE 17 -1 (-5650 2500)(-5650 2550);
WIRE 17 -1 (-5650 2450)(-5650 2500);
WIRE 17 -1 (-5650 2400)(-5650 2450);
WIRE 17 -1 (-5650 2350)(-5650 2400);
WIRE 17 -1 (-5650 2300)(-5650 2350);
WIRE 17 -1 (-5650 2250)(-5650 2300);
WIRE 17 -1 (-5650 2200)(-5650 2250);
WIRE 17 -1 (-5650 2150)(-5650 2200);
WIRE 17 -1 (-5650 2100)(-5650 2150);
WIRE 17 -1 (-5650 2050)(-5650 2100);
WIRE 17 -1 (-5650 2000)(-5650 2050);
WIRE 17 -1 (-5650 1950)(-5650 2000);
WIRE 17 -1 (-5650 1900)(-5650 1950);
WIRE 17 -1 (-5650 1850)(-5650 1900);
WIRE 17 -1 (-5650 1800)(-5650 1850);
WIRE 17 -1 (-5650 1750)(-5650 1800);
WIRE 17 -1 (-5650 1700)(-5650 1750);
WIRE 17 -1 (-5650 1650)(-5650 1700);
WIRE 17 -1 (-5650 1600)(-5650 1650);
WIRE 17 -1 (-5650 1550)(-5650 1600);
WIRE 17 -1 (-5650 800)(-5650 825);
WIRE 17 -1 (-5650 750)(-5650 800);
WIRE 17 -1 (-5650 825)(-6400 825);
FORCEPROP 2 LAST SIG_NAME M_H_CLK_DN<3:0>
J 0
(-6350 835);
DISPLAY 0.617021 (-6350 835);
PAINT ORANGE (-6350 835);
WIRE 17 -1 (-5650 700)(-5650 750);
WIRE 17 -1 (-5650 650)(-5650 700);
WIRE 17 -1 (-5650 1000)(-5650 1025);
WIRE 17 -1 (-5650 950)(-5650 1000);
WIRE 17 -1 (-5650 1025)(-6400 1025);
FORCEPROP 2 LAST SIG_NAME M_H_CLK_DP<3:0>
J 0
(-6350 1035);
DISPLAY 0.617021 (-6350 1035);
PAINT ORANGE (-6350 1035);
WIRE 17 -1 (-5650 900)(-5650 950);
WIRE 17 -1 (-5650 850)(-5650 900);
WIRE 17 -1 (-5650 1450)(-5650 1475);
WIRE 17 -1 (-5650 1400)(-5650 1450);
WIRE 17 -1 (-5650 1475)(-6400 1475);
FORCEPROP 2 LAST SIG_NAME M_H_ECC<7:0>
J 0
(-6350 1485);
DISPLAY 0.617021 (-6350 1485);
PAINT ORANGE (-6350 1485);
WIRE 17 -1 (-5650 1350)(-5650 1400);
WIRE 17 -1 (-5650 1300)(-5650 1350);
WIRE 17 -1 (-5650 1250)(-5650 1300);
WIRE 17 -1 (-5650 1200)(-5650 1250);
WIRE 17 -1 (-5650 1150)(-5650 1200);
WIRE 17 -1 (-5650 1100)(-5650 1150);
WIRE 16 -1 (-5050 525)(-6400 525);
FORCEPROP 2 LAST SIG_NAME M_H_C<2>
J 0
(-6350 535);
DISPLAY 0.617021 (-6350 535);
PAINT ORANGE (-6350 535);
WIRE 16 -1 (-5050 1075)(-5550 1075);
WIRE 16 -1 (-5050 1125)(-5550 1125);
WIRE 16 -1 (-5050 1175)(-5550 1175);
WIRE 16 -1 (-5050 1225)(-5550 1225);
WIRE 16 -1 (-5050 1275)(-5550 1275);
WIRE 16 -1 (-5050 1325)(-5550 1325);
WIRE 16 -1 (-5050 1375)(-5550 1375);
WIRE 16 -1 (-5050 1425)(-5550 1425);
WIRE 16 -1 (-5550 1525)(-5050 1525);
WIRE 16 -1 (-5550 1575)(-5050 1575);
WIRE 16 -1 (-5550 1625)(-5050 1625);
WIRE 16 -1 (-5050 1675)(-5550 1675);
WIRE 16 -1 (-5550 1725)(-5050 1725);
WIRE 16 -1 (-5550 1775)(-5050 1775);
WIRE 16 -1 (-5050 1825)(-5550 1825);
WIRE 16 -1 (-5550 1875)(-5050 1875);
WIRE 16 -1 (-5550 1925)(-5050 1925);
WIRE 16 -1 (-5550 1975)(-5050 1975);
WIRE 16 -1 (-5550 2025)(-5050 2025);
WIRE 16 -1 (-5050 825)(-5550 825);
WIRE 16 -1 (-5050 875)(-5550 875);
WIRE 16 -1 (-5050 925)(-5550 925);
WIRE 16 -1 (-5050 975)(-5550 975);
WIRE 16 -1 (-5050 625)(-5550 625);
WIRE 16 -1 (-5050 675)(-5550 675);
WIRE 16 -1 (-5050 725)(-5550 725);
WIRE 16 -1 (-5050 775)(-5550 775);
WIRE 16 -1 (-5550 2075)(-5050 2075);
WIRE 16 -1 (-5550 2125)(-5050 2125);
WIRE 16 -1 (-5550 2175)(-5050 2175);
WIRE 16 -1 (-5550 2225)(-5050 2225);
WIRE 16 -1 (-5050 2275)(-5550 2275);
WIRE 16 -1 (-5550 2325)(-5050 2325);
WIRE 16 -1 (-5550 2375)(-5050 2375);
WIRE 16 -1 (-5050 2425)(-5550 2425);
WIRE 16 -1 (-5550 2475)(-5050 2475);
WIRE 16 -1 (-5550 2525)(-5050 2525);
WIRE 16 -1 (-5550 2575)(-5050 2575);
WIRE 16 -1 (-5550 2625)(-5050 2625);
WIRE 16 -1 (-5050 2675)(-5550 2675);
WIRE 16 -1 (-5550 2725)(-5050 2725);
WIRE 16 -1 (-5550 2775)(-5050 2775);
WIRE 16 -1 (-5550 2825)(-5050 2825);
WIRE 16 -1 (-5550 2875)(-5050 2875);
WIRE 16 -1 (-5550 2925)(-5050 2925);
WIRE 16 -1 (-5550 2975)(-5050 2975);
WIRE 16 -1 (-5050 3025)(-5550 3025);
WIRE 16 -1 (-5550 3075)(-5050 3075);
WIRE 16 -1 (-5550 3125)(-5050 3125);
WIRE 16 -1 (-5550 3175)(-5050 3175);
WIRE 16 -1 (-5550 3225)(-5050 3225);
WIRE 16 -1 (-5550 3275)(-5050 3275);
WIRE 16 -1 (-5550 3325)(-5050 3325);
WIRE 16 -1 (-5050 3375)(-5550 3375);
WIRE 16 -1 (-5550 3425)(-5050 3425);
WIRE 16 -1 (-5550 3475)(-5050 3475);
WIRE 16 -1 (-5050 3525)(-5550 3525);
WIRE 16 -1 (-5550 3575)(-5050 3575);
WIRE 16 -1 (-5550 3625)(-5050 3625);
WIRE 16 -1 (-5050 3675)(-5550 3675);
WIRE 16 -1 (-5050 3725)(-5550 3725);
WIRE 16 -1 (-5050 3775)(-5550 3775);
WIRE 16 -1 (-5050 3825)(-5550 3825);
WIRE 16 -1 (-5050 3875)(-5550 3875);
WIRE 16 -1 (-5050 3925)(-5550 3925);
WIRE 16 -1 (-5050 3975)(-5550 3975);
WIRE 16 -1 (-5050 4025)(-5550 4025);
WIRE 16 -1 (-5050 4075)(-5550 4075);
WIRE 16 -1 (-5050 4125)(-5550 4125);
WIRE 16 -1 (-5050 4175)(-5550 4175);
WIRE 16 -1 (-5050 4225)(-5550 4225);
WIRE 16 -1 (-5050 4275)(-5550 4275);
WIRE 16 -1 (-5050 4325)(-5550 4325);
WIRE 16 -1 (-5050 4375)(-5550 4375);
WIRE 16 -1 (-5050 4425)(-5550 4425);
WIRE 16 -1 (-5050 4475)(-5550 4475);
WIRE 16 -1 (-5050 4525)(-5550 4525);
WIRE 16 -1 (-5050 4575)(-5550 4575);
WIRE 16 -1 (-5050 4625)(-5550 4625);
WIRE 16 -1 (-5050 4675)(-5550 4675);
WIRE 16 -1 (-3350 1425)(-2925 1425);
WIRE 16 -1 (-3350 1475)(-2925 1475);
WIRE 16 -1 (-3350 1525)(-2925 1525);
WIRE 16 -1 (-3350 1575)(-2925 1575);
WIRE 16 -1 (-3350 1925)(-2925 1925);
WIRE 16 -1 (-3350 1975)(-2925 1975);
WIRE 16 -1 (-3350 2025)(-2925 2025);
WIRE 16 -1 (-3350 975)(-2925 975);
WIRE 16 -1 (-3350 1025)(-2925 1025);
WIRE 16 -1 (-3350 1075)(-2925 1075);
WIRE 16 -1 (-3350 1125)(-2925 1125);
WIRE 16 -1 (-3350 1175)(-2925 1175);
WIRE 16 -1 (-3350 1225)(-2925 1225);
WIRE 16 -1 (-3350 1275)(-2925 1275);
WIRE 16 -1 (-3350 1325)(-2925 1325);
WIRE 16 -1 (-3350 1675)(-2925 1675);
WIRE 16 -1 (-3350 1725)(-2925 1725);
WIRE 16 -1 (-3350 1775)(-2925 1775);
WIRE 16 -1 (-3350 1825)(-2925 1825);
WIRE 16 -1 (-3350 825)(-2925 825);
WIRE 16 -1 (-3350 875)(-2925 875);
WIRE 16 -1 (-3350 725)(-2925 725);
WIRE 16 -1 (-3350 775)(-2925 775);
WIRE 16 -1 (-3350 525)(-2075 525);
FORCEPROP 2 LAST SIG_NAME M_H_PAR
J 0
(-2725 535);
DISPLAY 0.617021 (-2725 535);
PAINT ORANGE (-2725 535);
WIRE 16 -1 (-3350 575)(-2075 575);
FORCEPROP 2 LAST SIG_NAME M_H_ALERT_N
J 0
(-2725 585);
DISPLAY 0.617021 (-2725 585);
PAINT ORANGE (-2725 585);
WIRE 16 -1 (-3350 625)(-2075 625);
FORCEPROP 2 LAST SIG_NAME M_H_ACT_N
J 0
(-2725 635);
DISPLAY 0.617021 (-2725 635);
PAINT ORANGE (-2725 635);
WIRE 16 -1 (-3350 2075)(-2925 2075);
WIRE 16 -1 (-3350 2125)(-2925 2125);
WIRE 16 -1 (-3350 2175)(-2925 2175);
WIRE 16 -1 (-3350 2225)(-2925 2225);
WIRE 16 -1 (-3350 2275)(-2925 2275);
WIRE 16 -1 (-3350 2325)(-2925 2325);
WIRE 16 -1 (-3350 2375)(-2925 2375);
WIRE 16 -1 (-3350 2425)(-2925 2425);
WIRE 16 -1 (-3350 2475)(-2925 2475);
WIRE 16 -1 (-3350 2525)(-2925 2525);
WIRE 16 -1 (-3350 2575)(-2925 2575);
WIRE 16 -1 (-3350 2625)(-2925 2625);
WIRE 16 -1 (-3350 2675)(-2925 2675);
WIRE 16 -1 (-3350 2725)(-2925 2725);
WIRE 16 -1 (-3350 2775)(-2925 2775);
WIRE 16 -1 (-3350 3825)(-2925 3825);
WIRE 16 -1 (-3350 3875)(-2925 3875);
WIRE 16 -1 (-3350 3925)(-2925 3925);
WIRE 16 -1 (-3350 3975)(-2925 3975);
WIRE 16 -1 (-3350 4025)(-2925 4025);
WIRE 16 -1 (-3350 4075)(-2925 4075);
WIRE 16 -1 (-3350 2875)(-2925 2875);
WIRE 16 -1 (-3350 2925)(-2925 2925);
WIRE 16 -1 (-3350 2975)(-2925 2975);
WIRE 16 -1 (-3350 3025)(-2925 3025);
WIRE 16 -1 (-3350 3075)(-2925 3075);
WIRE 16 -1 (-3350 3125)(-2925 3125);
WIRE 16 -1 (-3350 3175)(-2925 3175);
WIRE 16 -1 (-3350 3225)(-2925 3225);
WIRE 16 -1 (-3350 3275)(-2925 3275);
WIRE 16 -1 (-3350 3325)(-2925 3325);
WIRE 16 -1 (-3350 3375)(-2925 3375);
WIRE 16 -1 (-3350 3425)(-2925 3425);
WIRE 16 -1 (-3350 3475)(-2925 3475);
WIRE 16 -1 (-3350 3525)(-2925 3525);
WIRE 16 -1 (-3350 3575)(-2925 3575);
WIRE 16 -1 (-3350 3625)(-2925 3625);
WIRE 16 -1 (-3350 3675)(-2925 3675);
WIRE 16 -1 (-3350 3725)(-2925 3725);
WIRE 16 -1 (-3350 4125)(-2925 4125);
WIRE 16 -1 (-3350 4175)(-2925 4175);
WIRE 16 -1 (-3350 4225)(-2925 4225);
WIRE 16 -1 (-3350 4275)(-2925 4275);
WIRE 16 -1 (-3350 4325)(-2925 4325);
WIRE 16 -1 (-3350 4375)(-2925 4375);
WIRE 16 -1 (-3350 4425)(-2925 4425);
WIRE 16 -1 (-3350 4475)(-2925 4475);
WIRE 16 -1 (-3350 4525)(-2925 4525);
WIRE 16 -1 (-3350 4575)(-2925 4575);
WIRE 16 -1 (-3350 4625)(-2925 4625);
WIRE 16 -1 (-3350 4675)(-2925 4675);
FORCENOTE
BOM_COST=PROC_SOCKET
(-7900 225) 0;
DISPLAY LEFT (-7900 225);
DISPLAY 1.723404 (-7900 225);
PAINT PURPLE (-7900 225);
FORCENOTE
ROOM=CPU1
(-7900 350) 0;
DISPLAY LEFT (-7900 350);
DISPLAY 1.723404 (-7900 350);
PAINT PURPLE (-7900 350);
QUIT
